G04 ================== begin FILE IDENTIFICATION RECORD ==================*
G04 Layout Name:  DAT6MTH3AD0_t6m_cm_d_brd_103112_274.brd*
G04 Film Name:    gnd1*
G04 File Format:  Gerber RS274X*
G04 File Origin:  Cadence Allegro 16.3-S048*
G04 Origin Date:  Tue Nov 26 10:18:26 2013*
G04 *
G04 Layer:  VIA CLASS/GND1*
G04 Layer:  PIN/GND1*
G04 Layer:  MANUFACTURING/PHOTOPLOT_OUTLINE*
G04 Layer:  ETCH/GND1*
G04 Layer:  DRAWING FORMAT/TITLE_BLOCK*
G04 Layer:  DRAWING FORMAT/TITLE_DATA_GND1*
G04 *
G04 Offset:    (0.00 0.00)*
G04 Mirror:    No*
G04 Mode:      Negative*
G04 Rotation:  0*
G04 FullContactRelief:  No*
G04 UndefLineWidth:     6.00*
G04 ================== end FILE IDENTIFICATION RECORD ====================*
%FSLAX25Y25*MOIN*%
%IR0*IPPOS*OFA0.00000B0.00000*MIA0B0*SFA1.00000B1.00000*%
%ADD10C,.03*%
%ADD17C,.06*%
%ADD46C,.061*%
%AMMACRO37*
4,1,36,0.0,.01,
-.001736,.009848,
-.00342,.009397,
-.005,.00866,
-.006428,.00766,
-.00766,.006428,
-.00866,.005,
-.009397,.00342,
-.009848,.001736,
-.01,0.0,
-.009848,-.001736,
-.009397,-.00342,
-.00866,-.005,
-.00766,-.006428,
-.006428,-.00766,
-.005,-.00866,
-.00342,-.009397,
-.001736,-.009848,
0.0,-.01,
.001736,-.009848,
.00342,-.009397,
.005,-.00866,
.006428,-.00766,
.00766,-.006428,
.00866,-.005,
.009397,-.00342,
.009848,-.001736,
.01,0.0,
.009848,.001736,
.009397,.00342,
.00866,.005,
.00766,.006428,
.006428,.00766,
.005,.00866,
.00342,.009397,
.001736,.009848,
0.0,.01,
0.0*
%
%ADD37MACRO37*%
%ADD34C,.026*%
%ADD21C,.053*%
%ADD11C,.08*%
%ADD36C,.072*%
%AMMACRO53*
4,1,16,.04526,.02758,
.049362,.019302,
.051963,.010437,
.052986,.001255,
.052399,-.007965,
.05022,-.016943,
.046515,-.025406,
.04526,-.02758,
.05033,-.03266,
.055237,-.023424,
.058465,-.013476,
.059917,-.003119,
.059548,.007332,
.057371,.017562,
.053449,.027257,
.05033,.03266,
.04526,.02758,
90.*
4,1,16,.02758,-.04526,
.019302,-.049362,
.010437,-.051963,
.001255,-.052986,
-.007965,-.052399,
-.016943,-.05022,
-.025406,-.046515,
-.02758,-.04526,
-.03266,-.05033,
-.023424,-.055237,
-.013476,-.058465,
-.003119,-.059917,
.007332,-.059548,
.017562,-.057371,
.027257,-.053449,
.03266,-.05033,
.02758,-.04526,
90.*
4,1,16,-.04526,-.02758,
-.049362,-.019302,
-.051963,-.010437,
-.052986,-.001255,
-.052399,.007965,
-.05022,.016943,
-.046515,.025406,
-.04526,.02758,
-.05033,.03266,
-.055237,.023424,
-.058465,.013476,
-.059917,.003119,
-.059548,-.007332,
-.057371,-.017562,
-.053449,-.027257,
-.05033,-.03266,
-.04526,-.02758,
90.*
4,1,16,-.02758,.04526,
-.019302,.049362,
-.010437,.051963,
-.001255,.052986,
.007965,.052399,
.016943,.05022,
.025406,.046515,
.02758,.04526,
.03266,.05033,
.023424,.055237,
.013476,.058465,
.003119,.059917,
-.007332,.059548,
-.017562,.057371,
-.027257,.053449,
-.03266,.05033,
-.02758,.04526,
90.*
%
%ADD53MACRO53*%
%ADD51C,.046*%
%ADD41C,.064*%
%ADD48C,.056*%
%ADD44C,.066*%
%ADD38C,.076*%
%AMMACRO32*
4,1,36,0.0,.004,
.000695,.003939,
.001368,.003759,
.002,.003464,
.002571,.003064,
.003064,.002571,
.003464,.002,
.003759,.001368,
.003939,.000695,
.004,0.0,
.003939,-.000695,
.003759,-.001368,
.003464,-.002,
.003064,-.002571,
.002571,-.003064,
.002,-.003464,
.001368,-.003759,
.000695,-.003939,
0.0,-.004,
-.000695,-.003939,
-.001368,-.003759,
-.002,-.003464,
-.002571,-.003064,
-.003064,-.002571,
-.003464,-.002,
-.003759,-.001368,
-.003939,-.000695,
-.004,0.0,
-.003939,.000695,
-.003759,.001368,
-.003464,.002,
-.003064,.002571,
-.002571,.003064,
-.002,.003464,
-.001368,.003759,
-.000695,.003939,
0.0,.004,
180.*
%
%ADD32MACRO32*%
%AMMACRO26*
4,1,36,0.0,.004,
.000695,.003939,
.001368,.003759,
.002,.003464,
.002571,.003064,
.003064,.002571,
.003464,.002,
.003759,.001368,
.003939,.000695,
.004,0.0,
.003939,-.000695,
.003759,-.001368,
.003464,-.002,
.003064,-.002571,
.002571,-.003064,
.002,-.003464,
.001368,-.003759,
.000695,-.003939,
0.0,-.004,
-.000695,-.003939,
-.001368,-.003759,
-.002,-.003464,
-.002571,-.003064,
-.003064,-.002571,
-.003464,-.002,
-.003759,-.001368,
-.003939,-.000695,
-.004,0.0,
-.003939,.000695,
-.003759,.001368,
-.003464,.002,
-.003064,.002571,
-.002571,.003064,
-.002,.003464,
-.001368,.003759,
-.000695,.003939,
0.0,.004,
270.*
%
%ADD26MACRO26*%
%ADD33C,.095*%
%ADD28C,.068*%
%AMMACRO22*
4,1,20,-.0075,-.07601,
-.01225,-.074283,
-.016628,-.071757,
-.020501,-.06851,
-.023751,-.064639,
-.026279,-.060263,
-.02801,-.055514,
-.028889,-.050536,
-.029,-.048,
-.029,-.0075,
-.022,-.0075,
-.022,-.048,
-.021666,-.05182,
-.020673,-.055523,
-.019053,-.058998,
-.016854,-.062139,
-.014142,-.064851,
-.011002,-.06705,
-.007526,-.06867,
-.0075,-.06868,
-.0075,-.07601,
180.*
4,1,20,.0075,-.07601,
.0075,-.06868,
.010977,-.067064,
.014121,-.064869,
.016836,-.062161,
.019039,-.059023,
.020664,-.05555,
.021661,-.051847,
.022,-.048028,
.022,-.048,
.022,-.0075,
.029,-.0075,
.029,-.048,
.028559,-.053035,
.027251,-.057917,
.025115,-.062498,
.022216,-.066638,
.018642,-.070212,
.014502,-.073111,
.009921,-.075247,
.0075,-.07601,
180.*
4,1,20,-.029,.0075,
-.029,.048,
-.028559,.053035,
-.027251,.057917,
-.025115,.062498,
-.022216,.066638,
-.018642,.070212,
-.014502,.073111,
-.009921,.075247,
-.0075,.07601,
-.0075,.06868,
-.010977,.067064,
-.014121,.064869,
-.016836,.062161,
-.019039,.059023,
-.020664,.05555,
-.021661,.051847,
-.022,.048028,
-.022,.048,
-.022,.0075,
-.029,.0075,
180.*
4,1,20,.022,.0075,
.022,.048,
.021666,.05182,
.020673,.055523,
.019053,.058998,
.016854,.062139,
.014142,.064851,
.011002,.06705,
.007526,.06867,
.0075,.06868,
.0075,.07601,
.01225,.074283,
.016628,.071757,
.020501,.06851,
.023751,.064639,
.026279,.060263,
.02801,.055514,
.028889,.050536,
.029,.048,
.029,.0075,
.022,.0075,
180.*
%
%ADD22MACRO22*%
%ADD19C,.077*%
%ADD23C,.089*%
%AMMACRO52*
4,1,16,.0711,.04282,
.077455,.029823,
.081457,.01592,
.082984,.001533,
.08199,-.0129,
.078504,-.026942,
.072633,-.040164,
.0711,-.04282,
.07619,-.04791,
.083352,-.033952,
.087981,-.018962,
.089937,-.003396,
.089161,.012273,
.085675,.027569,
.079586,.042027,
.07619,.04791,
.0711,.04282,
0.0*
4,1,16,.04282,-.0711,
.029823,-.077455,
.01592,-.081457,
.001533,-.082984,
-.0129,-.08199,
-.026942,-.078504,
-.040164,-.072633,
-.04282,-.0711,
-.04791,-.07619,
-.033952,-.083352,
-.018962,-.087981,
-.003396,-.089937,
.012273,-.089161,
.027569,-.085675,
.042027,-.079586,
.04791,-.07619,
.04282,-.0711,
0.0*
4,1,16,-.0711,-.04282,
-.077455,-.029823,
-.081457,-.01592,
-.082984,-.001533,
-.08199,.0129,
-.078504,.026942,
-.072633,.040164,
-.0711,.04282,
-.07619,.04791,
-.083352,.033952,
-.087981,.018962,
-.089937,.003396,
-.089161,-.012273,
-.085675,-.027569,
-.079586,-.042027,
-.07619,-.04791,
-.0711,-.04282,
0.0*
4,1,16,-.04282,.0711,
-.029823,.077455,
-.01592,.081457,
-.001533,.082984,
.0129,.08199,
.026942,.078504,
.040164,.072633,
.04282,.0711,
.04791,.07619,
.033952,.083352,
.018962,.087981,
.003396,.089937,
-.012273,.089161,
-.027569,.085675,
-.042027,.079586,
-.04791,.07619,
-.04282,.0711,
0.0*
%
%ADD52MACRO52*%
%AMMACRO40*
4,1,19,.08773,.07358,
.099174,.057228,
.107605,.039137,
.112766,.019857,
.114501,-.000026,
.112757,-.019909,
.107587,-.039186,
.099148,-.057273,
.08773,-.07358,
.09269,-.07855,
.104922,-.061261,
.113966,-.042111,
.119547,-.021681,
.121496,-.000593,
.119753,.020514,
.114371,.040997,
.105515,.060234,
.093452,.077642,
.09269,.07855,
.08773,.07358,
0.0*
4,1,19,.07358,-.08773,
.057228,-.099174,
.039137,-.107605,
.019857,-.112766,
-.000026,-.114501,
-.019909,-.112757,
-.039186,-.107587,
-.057273,-.099148,
-.07358,-.08773,
-.07855,-.09269,
-.061261,-.104922,
-.042111,-.113966,
-.021681,-.119547,
-.000593,-.121496,
.020514,-.119753,
.040997,-.114371,
.060234,-.105515,
.077642,-.093452,
.07855,-.09269,
.07358,-.08773,
0.0*
4,1,19,-.08773,-.07358,
-.099174,-.057228,
-.107605,-.039137,
-.112766,-.019857,
-.114501,.000026,
-.112757,.019909,
-.107587,.039186,
-.099148,.057273,
-.08773,.07358,
-.09269,.07855,
-.104922,.061261,
-.113966,.042111,
-.119547,.021681,
-.121496,.000593,
-.119753,-.020514,
-.114371,-.040997,
-.105515,-.060234,
-.093452,-.077642,
-.09269,-.07855,
-.08773,-.07358,
0.0*
4,1,19,-.07358,.08773,
-.057228,.099174,
-.039137,.107605,
-.019857,.112766,
.000026,.114501,
.019909,.112757,
.039186,.107587,
.057273,.099148,
.07358,.08773,
.07855,.09269,
.061261,.104922,
.042111,.113966,
.021681,.119547,
.000593,.121496,
-.020514,.119753,
-.040997,.114371,
-.060234,.105515,
-.077642,.093452,
-.07855,.09269,
-.07358,.08773,
0.0*
%
%ADD40MACRO40*%
%AMMACRO54*
4,1,15,.02438,.01377,
.026401,.009327,
.027619,.004601,
.027999,-.000265,
.027527,-.005123,
.02622,-.009825,
.02438,-.01377,
.02948,-.01887,
.032309,-.013464,
.034156,-.007649,
.034965,-.001602,
.034712,.004494,
.033405,.010454,
.031082,.016095,
.02948,.01887,
.02438,.01377,
90.*
4,1,15,.01377,-.02438,
.009327,-.026401,
.004601,-.027619,
-.000265,-.027999,
-.005123,-.027527,
-.009825,-.02622,
-.01377,-.02438,
-.01887,-.02948,
-.013464,-.032309,
-.007649,-.034156,
-.001602,-.034965,
.004494,-.034712,
.010454,-.033405,
.016095,-.031082,
.01887,-.02948,
.01377,-.02438,
90.*
4,1,15,-.02438,-.01377,
-.026401,-.009327,
-.027619,-.004601,
-.027999,.000265,
-.027527,.005123,
-.02622,.009825,
-.02438,.01377,
-.02948,.01887,
-.032309,.013464,
-.034156,.007649,
-.034965,.001602,
-.034712,-.004494,
-.033405,-.010454,
-.031082,-.016095,
-.02948,-.01887,
-.02438,-.01377,
90.*
4,1,15,-.01377,.02438,
-.009327,.026401,
-.004601,.027619,
.000265,.027999,
.005123,.027527,
.009825,.02622,
.01377,.02438,
.01887,.02948,
.013464,.032309,
.007649,.034156,
.001602,.034965,
-.004494,.034712,
-.010454,.033405,
-.016095,.031082,
-.01887,.02948,
-.01377,.02438,
90.*
%
%ADD54MACRO54*%
%AMMACRO30*
4,1,16,.06818,.0399,
.074073,.027454,
.077715,.014175,
.078996,.000464,
.077876,-.01326,
.07439,-.026582,
.068644,-.039096,
.06818,-.0399,
.07329,-.045,
.079991,-.03159,
.084261,-.01722,
.085971,-.002326,
.085069,.012638,
.081582,.027218,
.075616,.040971,
.07329,.045,
.06818,.0399,
0.0*
4,1,16,.0399,-.06818,
.027454,-.074073,
.014175,-.077715,
.000464,-.078996,
-.01326,-.077876,
-.026582,-.07439,
-.039096,-.068644,
-.0399,-.06818,
-.045,-.07329,
-.03159,-.079991,
-.01722,-.084261,
-.002326,-.085971,
.012638,-.085069,
.027218,-.081582,
.040971,-.075616,
.045,-.07329,
.0399,-.06818,
0.0*
4,1,16,-.06818,-.0399,
-.074073,-.027454,
-.077715,-.014175,
-.078996,-.000464,
-.077876,.01326,
-.07439,.026582,
-.068644,.039096,
-.06818,.0399,
-.07329,.045,
-.079991,.03159,
-.084261,.01722,
-.085971,.002326,
-.085069,-.012638,
-.081582,-.027218,
-.075616,-.040971,
-.07329,-.045,
-.06818,-.0399,
0.0*
4,1,16,-.0399,.06818,
-.027454,.074073,
-.014175,.077715,
-.000464,.078996,
.01326,.077876,
.026582,.07439,
.039096,.068644,
.0399,.06818,
.045,.07329,
.03159,.079991,
.01722,.084261,
.002326,.085971,
-.012638,.085069,
-.027218,.081582,
-.040971,.075616,
-.045,.07329,
-.0399,.06818,
0.0*
%
%ADD30MACRO30*%
%AMMACRO47*
4,1,15,.02291,.0123,
.024698,.008135,
.025735,.003723,
.025991,-.000803,
.025456,-.005304,
.024149,-.009644,
.02291,-.0123,
.02803,-.01742,
.030629,-.012288,
.032298,-.006783,
.032985,-.001071,
.03267,.004673,
.031362,.010275,
.029101,.015565,
.02803,.01742,
.02291,.0123,
90.*
4,1,15,.0123,-.02291,
.008135,-.024698,
.003723,-.025735,
-.000803,-.025991,
-.005304,-.025456,
-.009644,-.024149,
-.0123,-.02291,
-.01742,-.02803,
-.012288,-.030629,
-.006783,-.032298,
-.001071,-.032985,
.004673,-.03267,
.010275,-.031362,
.015565,-.029101,
.01742,-.02803,
.0123,-.02291,
90.*
4,1,15,-.02291,-.0123,
-.024698,-.008135,
-.025735,-.003723,
-.025991,.000803,
-.025456,.005304,
-.024149,.009644,
-.02291,.0123,
-.02803,.01742,
-.030629,.012288,
-.032298,.006783,
-.032985,.001071,
-.03267,-.004673,
-.031362,-.010275,
-.029101,-.015565,
-.02803,-.01742,
-.02291,-.0123,
90.*
4,1,15,-.0123,.02291,
-.008135,.024698,
-.003723,.025735,
.000803,.025991,
.005304,.025456,
.009644,.024149,
.0123,.02291,
.01742,.02803,
.012288,.030629,
.006783,.032298,
.001071,.032985,
-.004673,.03267,
-.010275,.031362,
-.015565,.029101,
-.01742,.02803,
-.0123,.02291,
90.*
%
%ADD47MACRO47*%
%AMMACRO27*
4,1,15,.02438,.01377,
.026401,.009327,
.027619,.004601,
.027999,-.000265,
.027527,-.005123,
.02622,-.009825,
.02438,-.01377,
.02948,-.01887,
.032309,-.013464,
.034156,-.007649,
.034965,-.001602,
.034712,.004494,
.033405,.010454,
.031082,.016095,
.02948,.01887,
.02438,.01377,
0.0*
4,1,15,.01377,-.02438,
.009327,-.026401,
.004601,-.027619,
-.000265,-.027999,
-.005123,-.027527,
-.009825,-.02622,
-.01377,-.02438,
-.01887,-.02948,
-.013464,-.032309,
-.007649,-.034156,
-.001602,-.034965,
.004494,-.034712,
.010454,-.033405,
.016095,-.031082,
.01887,-.02948,
.01377,-.02438,
0.0*
4,1,15,-.02438,-.01377,
-.026401,-.009327,
-.027619,-.004601,
-.027999,.000265,
-.027527,.005123,
-.02622,.009825,
-.02438,.01377,
-.02948,.01887,
-.032309,.013464,
-.034156,.007649,
-.034965,.001602,
-.034712,-.004494,
-.033405,-.010454,
-.031082,-.016095,
-.02948,-.01887,
-.02438,-.01377,
0.0*
4,1,15,-.01377,.02438,
-.009327,.026401,
-.004601,.027619,
.000265,.027999,
.005123,.027527,
.009825,.02622,
.01377,.02438,
.01887,.02948,
.013464,.032309,
.007649,.034156,
.001602,.034965,
-.004494,.034712,
-.010454,.033405,
-.016095,.031082,
-.01887,.02948,
-.01377,.02438,
0.0*
%
%ADD27MACRO27*%
%AMMACRO20*
4,1,15,.0218,.01119,
.023412,.007234,
.024313,.003059,
.024474,-.001209,
.023893,-.005441,
.022585,-.009507,
.0218,-.01119,
.02694,-.01633,
.029366,-.011404,
.030901,-.006131,
.031496,-.000672,
.031134,.004807,
.029826,.010141,
.027612,.015166,
.02694,.01633,
.0218,.01119,
90.*
4,1,15,.01119,-.0218,
.007234,-.023412,
.003059,-.024313,
-.001209,-.024474,
-.005441,-.023893,
-.009507,-.022585,
-.01119,-.0218,
-.01633,-.02694,
-.011404,-.029366,
-.006131,-.030901,
-.000672,-.031496,
.004807,-.031134,
.010141,-.029826,
.015166,-.027612,
.01633,-.02694,
.01119,-.0218,
90.*
4,1,15,-.0218,-.01119,
-.023412,-.007234,
-.024313,-.003059,
-.024474,.001209,
-.023893,.005441,
-.022585,.009507,
-.0218,.01119,
-.02694,.01633,
-.029366,.011404,
-.030901,.006131,
-.031496,.000672,
-.031134,-.004807,
-.029826,-.010141,
-.027612,-.015166,
-.02694,-.01633,
-.0218,-.01119,
90.*
4,1,15,-.01119,.0218,
-.007234,.023412,
-.003059,.024313,
.001209,.024474,
.005441,.023893,
.009507,.022585,
.01119,.0218,
.01633,.02694,
.011404,.029366,
.006131,.030901,
.000672,.031496,
-.004807,.031134,
-.010141,.029826,
-.015166,.027612,
-.01633,.02694,
-.01119,.0218,
90.*
%
%ADD20MACRO20*%
%AMMACRO29*
4,1,16,.0273,.01669,
.029783,.011696,
.031362,.006346,
.031987,.000804,
.031641,-.004763,
.030333,-.010185,
.028104,-.015297,
.0273,-.01669,
.03237,-.02176,
.035657,-.015808,
.03786,-.009377,
.038913,-.00266,
.038784,.004138,
.037476,.01081,
.03503,.017153,
.03237,.02176,
.0273,.01669,
0.0*
4,1,16,.01669,-.0273,
.011696,-.029783,
.006346,-.031362,
.000804,-.031987,
-.004763,-.031641,
-.010185,-.030333,
-.015297,-.028104,
-.01669,-.0273,
-.02176,-.03237,
-.015808,-.035657,
-.009377,-.03786,
-.00266,-.038913,
.004138,-.038784,
.01081,-.037476,
.017153,-.03503,
.02176,-.03237,
.01669,-.0273,
0.0*
4,1,16,-.0273,-.01669,
-.029783,-.011696,
-.031362,-.006346,
-.031987,-.000804,
-.031641,.004763,
-.030333,.010185,
-.028104,.015297,
-.0273,.01669,
-.03237,.02176,
-.035657,.015808,
-.03786,.009377,
-.038913,.00266,
-.038784,-.004138,
-.037476,-.01081,
-.03503,-.017153,
-.03237,-.02176,
-.0273,-.01669,
0.0*
4,1,16,-.01669,.0273,
-.011696,.029783,
-.006346,.031362,
-.000804,.031987,
.004763,.031641,
.010185,.030333,
.015297,.028104,
.01669,.0273,
.02176,.03237,
.015808,.035657,
.009377,.03786,
.00266,.038913,
-.004138,.038784,
-.01081,.037476,
-.017153,.03503,
-.02176,.03237,
-.01669,.0273,
0.0*
%
%ADD29MACRO29*%
%ADD18C,.15*%
%ADD31C,.148*%
%ADD39C,.188*%
%AMMACRO25*
4,1,36,0.0,.004,
.000695,.003939,
.001368,.003759,
.002,.003464,
.002571,.003064,
.003064,.002571,
.003464,.002,
.003759,.001368,
.003939,.000695,
.004,0.0,
.003939,-.000695,
.003759,-.001368,
.003464,-.002,
.003064,-.002571,
.002571,-.003064,
.002,-.003464,
.001368,-.003759,
.000695,-.003939,
0.0,-.004,
-.000695,-.003939,
-.001368,-.003759,
-.002,-.003464,
-.002571,-.003064,
-.003064,-.002571,
-.003464,-.002,
-.003759,-.001368,
-.003939,-.000695,
-.004,0.0,
-.003939,.000695,
-.003759,.001368,
-.003464,.002,
-.003064,.002571,
-.002571,.003064,
-.002,.003464,
-.001368,.003759,
-.000695,.003939,
0.0,.004,
90.*
%
%ADD25MACRO25*%
%AMMACRO14*
4,1,36,0.0,.004,
.000695,.003939,
.001368,.003759,
.002,.003464,
.002571,.003064,
.003064,.002571,
.003464,.002,
.003759,.001368,
.003939,.000695,
.004,0.0,
.003939,-.000695,
.003759,-.001368,
.003464,-.002,
.003064,-.002571,
.002571,-.003064,
.002,-.003464,
.001368,-.003759,
.000695,-.003939,
0.0,-.004,
-.000695,-.003939,
-.001368,-.003759,
-.002,-.003464,
-.002571,-.003064,
-.003064,-.002571,
-.003464,-.002,
-.003759,-.001368,
-.003939,-.000695,
-.004,0.0,
-.003939,.000695,
-.003759,.001368,
-.003464,.002,
-.003064,.002571,
-.002571,.003064,
-.002,.003464,
-.001368,.003759,
-.000695,.003939,
0.0,.004,
0.0*
%
%ADD14MACRO14*%
%AMMACRO35*
4,1,36,0.0,.004,
.000695,.003939,
.001368,.003759,
.002,.003464,
.002571,.003064,
.003064,.002571,
.003464,.002,
.003759,.001368,
.003939,.000695,
.004,0.0,
.003939,-.000695,
.003759,-.001368,
.003464,-.002,
.003064,-.002571,
.002571,-.003064,
.002,-.003464,
.001368,-.003759,
.000695,-.003939,
0.0,-.004,
-.000695,-.003939,
-.001368,-.003759,
-.002,-.003464,
-.002571,-.003064,
-.003064,-.002571,
-.003464,-.002,
-.003759,-.001368,
-.003939,-.000695,
-.004,0.0,
-.003939,.000695,
-.003759,.001368,
-.003464,.002,
-.003064,.002571,
-.002571,.003064,
-.002,.003464,
-.001368,.003759,
-.000695,.003939,
0.0,.004,
.001*
%
%ADD35MACRO35*%
%AMMACRO50*
4,1,13,.01917,.00857,
.020367,.005111,
.020945,.001497,
.020887,-.002163,
.020194,-.005757,
.01917,-.00857,
.02438,-.01377,
.026401,-.009327,
.027619,-.004601,
.027999,.000265,
.027527,.005123,
.02622,.009825,
.02438,.01377,
.01917,.00857,
270.*
4,1,13,.00857,-.01917,
.005111,-.020367,
.001497,-.020945,
-.002163,-.020887,
-.005757,-.020194,
-.00857,-.01917,
-.01377,-.02438,
-.009327,-.026401,
-.004601,-.027619,
.000265,-.027999,
.005123,-.027527,
.009825,-.02622,
.01377,-.02438,
.00857,-.01917,
270.*
4,1,13,-.01917,-.00857,
-.020367,-.005111,
-.020945,-.001497,
-.020887,.002163,
-.020194,.005757,
-.01917,.00857,
-.02438,.01377,
-.026401,.009327,
-.027619,.004601,
-.027999,-.000265,
-.027527,-.005123,
-.02622,-.009825,
-.02438,-.01377,
-.01917,-.00857,
270.*
4,1,13,-.00857,.01917,
-.005111,.020367,
-.001497,.020945,
.002163,.020887,
.005757,.020194,
.00857,.01917,
.01377,.02438,
.009327,.026401,
.004601,.027619,
-.000265,.027999,
-.005123,.027527,
-.009825,.02622,
-.01377,.02438,
-.00857,.01917,
270.*
%
%ADD50MACRO50*%
%AMMACRO42*
4,1,15,.02438,.01377,
.026401,.009327,
.027619,.004601,
.027999,-.000265,
.027527,-.005123,
.02622,-.009825,
.02438,-.01377,
.02948,-.01887,
.032309,-.013464,
.034156,-.007649,
.034965,-.001602,
.034712,.004494,
.033405,.010454,
.031082,.016095,
.02948,.01887,
.02438,.01377,
270.*
4,1,15,.01377,-.02438,
.009327,-.026401,
.004601,-.027619,
-.000265,-.027999,
-.005123,-.027527,
-.009825,-.02622,
-.01377,-.02438,
-.01887,-.02948,
-.013464,-.032309,
-.007649,-.034156,
-.001602,-.034965,
.004494,-.034712,
.010454,-.033405,
.016095,-.031082,
.01887,-.02948,
.01377,-.02438,
270.*
4,1,15,-.02438,-.01377,
-.026401,-.009327,
-.027619,-.004601,
-.027999,.000265,
-.027527,.005123,
-.02622,.009825,
-.02438,.01377,
-.02948,.01887,
-.032309,.013464,
-.034156,.007649,
-.034965,.001602,
-.034712,-.004494,
-.033405,-.010454,
-.031082,-.016095,
-.02948,-.01887,
-.02438,-.01377,
270.*
4,1,15,-.01377,.02438,
-.009327,.026401,
-.004601,.027619,
.000265,.027999,
.005123,.027527,
.009825,.02622,
.01377,.02438,
.01887,.02948,
.013464,.032309,
.007649,.034156,
.001602,.034965,
-.004494,.034712,
-.010454,.033405,
-.016095,.031082,
-.01887,.02948,
-.01377,.02438,
270.*
%
%ADD42MACRO42*%
%AMMACRO16*
4,1,15,.02438,.01377,
.026401,.009327,
.027619,.004601,
.027999,-.000265,
.027527,-.005123,
.02622,-.009825,
.02438,-.01377,
.02948,-.01887,
.032309,-.013464,
.034156,-.007649,
.034965,-.001602,
.034712,.004494,
.033405,.010454,
.031082,.016095,
.02948,.01887,
.02438,.01377,
180.*
4,1,15,.01377,-.02438,
.009327,-.026401,
.004601,-.027619,
-.000265,-.027999,
-.005123,-.027527,
-.009825,-.02622,
-.01377,-.02438,
-.01887,-.02948,
-.013464,-.032309,
-.007649,-.034156,
-.001602,-.034965,
.004494,-.034712,
.010454,-.033405,
.016095,-.031082,
.01887,-.02948,
.01377,-.02438,
180.*
4,1,15,-.02438,-.01377,
-.026401,-.009327,
-.027619,-.004601,
-.027999,.000265,
-.027527,.005123,
-.02622,.009825,
-.02438,.01377,
-.02948,.01887,
-.032309,.013464,
-.034156,.007649,
-.034965,.001602,
-.034712,-.004494,
-.033405,-.010454,
-.031082,-.016095,
-.02948,-.01887,
-.02438,-.01377,
180.*
4,1,15,-.01377,.02438,
-.009327,.026401,
-.004601,.027619,
.000265,.027999,
.005123,.027527,
.009825,.02622,
.01377,.02438,
.01887,.02948,
.013464,.032309,
.007649,.034156,
.001602,.034965,
-.004494,.034712,
-.010454,.033405,
-.016095,.031082,
-.01887,.02948,
-.01377,.02438,
180.*
%
%ADD16MACRO16*%
%AMMACRO45*
4,1,15,.02475,.01414,
.026829,.009627,
.028094,.004822,
.028504,-.000129,
.028049,-.005077,
.026741,-.009871,
.02475,-.01414,
.02984,-.01923,
.032726,-.013756,
.034617,-.007864,
.035457,-.001734,
.03522,.00445,
.033912,.010498,
.031574,.016227,
.02984,.01923,
.02475,.01414,
180.*
4,1,15,.01414,-.02475,
.009627,-.026829,
.004822,-.028094,
-.000129,-.028504,
-.005077,-.028049,
-.009871,-.026741,
-.01414,-.02475,
-.01923,-.02984,
-.013756,-.032726,
-.007864,-.034617,
-.001734,-.035457,
.00445,-.03522,
.010498,-.033912,
.016227,-.031574,
.01923,-.02984,
.01414,-.02475,
180.*
4,1,15,-.02475,-.01414,
-.026829,-.009627,
-.028094,-.004822,
-.028504,.000129,
-.028049,.005077,
-.026741,.009871,
-.02475,.01414,
-.02984,.01923,
-.032726,.013756,
-.034617,.007864,
-.035457,.001734,
-.03522,-.00445,
-.033912,-.010498,
-.031574,-.016227,
-.02984,-.01923,
-.02475,-.01414,
180.*
4,1,15,-.01414,.02475,
-.009627,.026829,
-.004822,.028094,
.000129,.028504,
.005077,.028049,
.009871,.026741,
.01414,.02475,
.01923,.02984,
.013756,.032726,
.007864,.034617,
.001734,.035457,
-.00445,.03522,
-.010498,.033912,
-.016227,.031574,
-.01923,.02984,
-.01414,.02475,
180.*
%
%ADD45MACRO45*%
%AMMACRO43*
4,1,16,.02657,.01597,
.02894,.011114,
.03043,.005919,
.030995,.000545,
.030619,-.004845,
.029313,-.010088,
.027115,-.015025,
.02657,-.01597,
.03164,-.02104,
.034813,-.015226,
.036928,-.00895,
.037921,-.002401,
.037762,.00422,
.036455,.010713,
.034041,.016881,
.03164,.02104,
.02657,.01597,
270.*
4,1,16,.01597,-.02657,
.011114,-.02894,
.005919,-.03043,
.000545,-.030995,
-.004845,-.030619,
-.010088,-.029313,
-.015025,-.027115,
-.01597,-.02657,
-.02104,-.03164,
-.015226,-.034813,
-.00895,-.036928,
-.002401,-.037921,
.00422,-.037762,
.010713,-.036455,
.016881,-.034041,
.02104,-.03164,
.01597,-.02657,
270.*
4,1,16,-.02657,-.01597,
-.02894,-.011114,
-.03043,-.005919,
-.030995,-.000545,
-.030619,.004845,
-.029313,.010088,
-.027115,.015025,
-.02657,.01597,
-.03164,.02104,
-.034813,.015226,
-.036928,.00895,
-.037921,.002401,
-.037762,-.00422,
-.036455,-.010713,
-.034041,-.016881,
-.03164,-.02104,
-.02657,-.01597,
270.*
4,1,16,-.01597,.02657,
-.011114,.02894,
-.005919,.03043,
-.000545,.030995,
.004845,.030619,
.010088,.029313,
.015025,.027115,
.01597,.02657,
.02104,.03164,
.015226,.034813,
.00895,.036928,
.002401,.037921,
-.00422,.037762,
-.010713,.036455,
-.016881,.034041,
-.02104,.03164,
-.01597,.02657,
270.*
%
%ADD43MACRO43*%
%AMMACRO49*
4,1,16,.0302,.01959,
.033143,.014048,
.035079,.00808,
.035949,.001865,
.035727,-.004405,
.034419,-.010542,
.032065,-.016359,
.0302,-.01959,
.03524,-.02464,
.038983,-.018146,
.041542,-.011101,
.042839,-.003719,
.042834,.003777,
.041527,.011157,
.038959,.018199,
.03524,.02464,
.0302,.01959,
270.*
4,1,16,.01959,-.0302,
.014048,-.033143,
.00808,-.035079,
.001865,-.035949,
-.004405,-.035727,
-.010542,-.034419,
-.016359,-.032065,
-.01959,-.0302,
-.02464,-.03524,
-.018146,-.038983,
-.011101,-.041542,
-.003719,-.042839,
.003777,-.042834,
.011157,-.041527,
.018199,-.038959,
.02464,-.03524,
.01959,-.0302,
270.*
4,1,16,-.0302,-.01959,
-.033143,-.014048,
-.035079,-.00808,
-.035949,-.001865,
-.035727,.004405,
-.034419,.010542,
-.032065,.016359,
-.0302,.01959,
-.03524,.02464,
-.038983,.018146,
-.041542,.011101,
-.042839,.003719,
-.042834,-.003777,
-.041527,-.011157,
-.038959,-.018199,
-.03524,-.02464,
-.0302,-.01959,
270.*
4,1,16,-.01959,.0302,
-.014048,.033143,
-.00808,.035079,
-.001865,.035949,
.004405,.035727,
.010542,.034419,
.016359,.032065,
.01959,.0302,
.02464,.03524,
.018146,.038983,
.011101,.041542,
.003719,.042839,
-.003777,.042834,
-.011157,.041527,
-.018199,.038959,
-.02464,.03524,
-.01959,.0302,
270.*
%
%ADD49MACRO49*%
%AMMACRO24*
4,1,17,.03056,.01996,
.033562,.01435,
.035544,.008304,
.036446,.002006,
.03624,-.004353,
.034934,-.01058,
.032566,-.016486,
.03056,-.01996,
.0356,-.025,
.0394,-.018438,
.042004,-.011316,
.043331,-.003851,
.043341,.003732,
.042034,.011201,
.039451,.018331,
.035668,.024903,
.0356,.025,
.03056,.01996,
270.*
4,1,17,.01996,-.03056,
.01435,-.033562,
.008304,-.035544,
.002006,-.036446,
-.004353,-.03624,
-.01058,-.034934,
-.016486,-.032566,
-.01996,-.03056,
-.025,-.0356,
-.018438,-.0394,
-.011316,-.042004,
-.003851,-.043331,
.003732,-.043341,
.011201,-.042034,
.018331,-.039451,
.024903,-.035668,
.025,-.0356,
.01996,-.03056,
270.*
4,1,17,-.03056,-.01996,
-.033562,-.01435,
-.035544,-.008304,
-.036446,-.002006,
-.03624,.004353,
-.034934,.01058,
-.032566,.016486,
-.03056,.01996,
-.0356,.025,
-.0394,.018438,
-.042004,.011316,
-.043331,.003851,
-.043341,-.003732,
-.042034,-.011201,
-.039451,-.018331,
-.035668,-.024903,
-.0356,-.025,
-.03056,-.01996,
270.*
4,1,17,-.01996,.03056,
-.01435,.033562,
-.008304,.035544,
-.002006,.036446,
.004353,.03624,
.01058,.034934,
.016486,.032566,
.01996,.03056,
.025,.0356,
.018438,.0394,
.011316,.042004,
.003851,.043331,
-.003732,.043341,
-.011201,.042034,
-.018331,.039451,
-.024903,.035668,
-.025,.0356,
-.01996,.03056,
270.*
%
%ADD24MACRO24*%
%ADD55C,.006*%
%ADD60C,.07006*%
%ADD61C,.09712*%
%ADD58C,.09109*%
%ADD62C,.07809*%
%ADD63C,.07909*%
%ADD59C,.15206*%
%ADD57C,.15806*%
%ADD56C,.19786*%
G75*
%LPD*%
G75*
G36*
G01X-1043962Y-705877D02*
X2300638D01*
Y2342823D01*
X-1043962D01*
Y-705877D01*
G37*
%LPC*%
G75*
G36*
G01X-10373Y819654D02*
G02X-9873Y819154I0J-500D01*
G01Y657141D01*
X828D01*
X2000Y658313D01*
Y659188D01*
X2004D01*
Y664173D01*
G02X7874Y670043I5870J0D01*
G01X40787D01*
G03X50665Y679921I0J9878D01*
G01Y798726D01*
G02X51165Y799226I500J0D01*
G01X326472D01*
G02X326972Y798726I0J-500D01*
G01Y792323D01*
G03X338461I5744J0D01*
G01Y798726D01*
G02X338961Y799226I500J0D01*
G01X378047D01*
G02X378547Y798726I0J-500D01*
G01Y741142D01*
G03X408933I15193J0D01*
G01Y798726D01*
G02X409433Y799226I500J0D01*
G01X684740D01*
G02X685240Y798726I0J-500D01*
G01Y792323D01*
G03X696728I5744J0D01*
G01Y798726D01*
G02X697228Y799226I500J0D01*
G01X736315D01*
G02X736815Y798726I0J-500D01*
G01Y679921D01*
G03X746693Y670043I9878J0D01*
G01X779528D01*
G02X785398Y664173I0J-5870D01*
G01Y297835D01*
G02X781496Y293933I-3902J0D01*
G01X780315D01*
G03X772405Y286024I0J-7910D01*
G01Y132480D01*
G03X780315Y124571I7910J1D01*
G01X781496D01*
G02X785398Y120669I0J-3902D01*
G01Y7874D01*
G02X779528Y2004I-5870J0D01*
G01X7874D01*
G02X2004Y7874I0J5870D01*
G01Y115354D01*
G02X5906Y119256I3902J0D01*
G01X25591D01*
G03X33500Y127165I0J7909D01*
G01Y272835D01*
G03X25591Y280744I-7909J0D01*
G01X5906D01*
G02X2004Y284646I0J3902D01*
G01Y651126D01*
X828Y652302D01*
X-9873D01*
Y632227D01*
X-9874Y632226D01*
Y2500D01*
G02X-10374Y2000I-500J0D01*
G01X-63929D01*
G02X-69803Y7874I0J5874D01*
G01Y813780D01*
G02X-63929Y819654I5874J0D01*
G01X-10373D01*
G37*
%LPD*%
G75*
G36*
G01X358051Y38554D02*
G02X356879Y35852I-3703J1D01*
G01X356556D01*
G03X356056Y35352I0J-500D01*
G01Y35269D01*
G02X352660Y35258I-1709J3285D01*
G01Y35354D01*
G03X352160Y35854I-500J0D01*
G01X351814D01*
G02X351817Y41256I2534J2700D01*
G01X352162D01*
G03X352662Y41756I0J500D01*
G01Y41851D01*
G02X356056Y41839I1685J-3297D01*
G01Y41756D01*
G03X356556Y41256I500J0D01*
G01X356879D01*
G02X358051Y38554I-2531J-2703D01*
G37*
G36*
G01X397421D02*
G02X396249Y35852I-3703J1D01*
G01X395926D01*
G03X395426Y35352I0J-500D01*
G01Y35269D01*
G02X392030Y35258I-1709J3285D01*
G01Y35354D01*
G03X391530Y35854I-500J0D01*
G01X391184D01*
G02X391187Y41256I2534J2700D01*
G01X391532D01*
G03X392032Y41756I0J500D01*
G01Y41851D01*
G02X395426Y41839I1685J-3297D01*
G01Y41756D01*
G03X395926Y41256I500J0D01*
G01X396249D01*
G02X397421Y38554I-2531J-2703D01*
G37*
G36*
G01X583956Y65176D02*
G02X579954Y69178I0J4002D01*
G02X587858I3952J0D01*
G01Y69078D01*
G02X583956Y65176I-3902J0D01*
G37*
G36*
G01X608614D02*
G02X604612Y69178I0J4002D01*
G02X612516I3952J0D01*
G01Y69078D01*
G02X608614Y65176I-3902J0D01*
G37*
G36*
G01X610314Y189040D02*
X613090D01*
X615052Y187078D01*
Y177609D01*
X613090Y175647D01*
X610314D01*
X608352Y177609D01*
Y187078D01*
X610314Y189040D01*
G37*
G36*
G01X624137Y186553D02*
X625463D01*
X626400Y185616D01*
Y179290D01*
X625463Y178353D01*
X624137D01*
X623200Y179290D01*
Y185616D01*
X624137Y186553D01*
G37*
G36*
G01X610314Y204040D02*
X613090D01*
X615052Y202078D01*
Y192609D01*
X613090Y190647D01*
X610314D01*
X608352Y192609D01*
Y202078D01*
X610314Y204040D01*
G37*
G36*
G01X634299Y201721D02*
X635625D01*
X636562Y200784D01*
Y194458D01*
X635625Y193521D01*
X634299D01*
X633362Y194458D01*
Y200784D01*
X634299Y201721D01*
G37*
G36*
G01X586535Y255503D02*
X591248D01*
X591473Y255278D01*
Y253037D01*
X591207Y252771D01*
X586641D01*
X586375Y253037D01*
Y255343D01*
X586535Y255503D01*
G37*
G36*
G01X586481Y260299D02*
X591194D01*
X591419Y260074D01*
Y257833D01*
X591153Y257567D01*
X586587D01*
X586321Y257833D01*
Y260139D01*
X586481Y260299D01*
G37*
G36*
G01X258370Y253327D02*
G02X260975Y251992I1148J-969D01*
G01X260942Y251863D01*
X261012Y251610D01*
X263666Y248956D01*
Y245187D01*
X268742Y240112D01*
Y234897D01*
X269713Y233926D01*
X284270D01*
X298947Y219248D01*
X302433D01*
X333572Y188110D01*
Y123313D01*
X333667Y123181D01*
G02X332268Y120806I-1214J-884D01*
G01X332153Y120821D01*
X331935Y120746D01*
X326933Y115744D01*
X325194D01*
X324060Y114610D01*
Y106737D01*
X325628Y105170D01*
Y95820D01*
X324643Y94836D01*
G03X324498Y94446I354J-353D01*
G02X322891Y92839I-1498J-109D01*
G03X322501Y92694I-37J-499D01*
G01X321710Y91902D01*
Y90221D01*
X321880Y89968D01*
X322023Y89911D01*
G02Y87123I-560J-1394D01*
G03X321709Y86659I186J-464D01*
G01X321710Y78102D01*
G03X321978Y77658I500J-1D01*
G02Y74996I-695J-1331D01*
G01X321854Y74931D01*
X321710Y74692D01*
Y72939D01*
X320649Y71878D01*
X268548D01*
X265448Y74979D01*
Y81128D01*
X266638Y82319D01*
Y88323D01*
X266529Y88460D01*
G02Y90334I1174J937D01*
G01X266638Y90471D01*
Y99505D01*
X264790Y101354D01*
Y101468D01*
X264674Y101607D01*
G02Y103525I1156J959D01*
G01X264790Y103664D01*
Y106956D01*
X264791Y106957D01*
Y114943D01*
X263284Y116450D01*
X251911D01*
X249118Y119242D01*
Y134093D01*
X228150Y155061D01*
Y198011D01*
X222618Y203543D01*
Y230242D01*
X221168Y231692D01*
Y250288D01*
X225149Y254268D01*
X233774D01*
X233793Y254270D01*
G02X234015I111J-1498D01*
G01X234034Y254268D01*
X235039D01*
X238002Y257231D01*
X238077Y257432D01*
X238070Y257541D01*
G02X239588Y259141I1499J98D01*
G03X240094Y259641I6J500D01*
G01Y261155D01*
X239862Y261387D01*
Y262952D01*
X240356Y263445D01*
G03X240401Y264100I-354J353D01*
G01X239699Y265026D01*
X239873Y265958D01*
X239875Y265969D01*
Y265971D01*
X240146Y266331D01*
G03X240226Y266770I-400J300D01*
G01X240140Y267068D01*
X239559Y268090D01*
X239633Y269447D01*
X241014Y270824D01*
X253518D01*
X254892Y269450D01*
Y254288D01*
X256030Y253150D01*
X257988D01*
G03X258370Y253327I0J500D01*
G37*
G54D60*
X-26872Y754493D03*
Y738493D03*
Y248533D03*
Y232533D03*
Y141213D03*
Y125213D03*
X-44872Y754493D03*
Y738493D03*
Y248533D03*
Y232533D03*
Y141213D03*
Y125213D03*
G54D61*
X151969Y98622D03*
G54D58*
X43898Y231457D03*
Y168544D03*
G54D62*
X414961Y98622D03*
G54D63*
X434102Y232640D03*
Y311875D03*
G54D59*
X25455Y356832D03*
Y303232D03*
G54D57*
X354331Y349606D03*
Y247244D03*
X102362Y349606D03*
Y247244D03*
G54D56*
X413386Y377165D03*
%LPC*%
G75*
G36*
G01X241034Y269307D02*
G02X241544Y269697I488J-110D01*
G03X242139Y269790I70J1500D01*
G01X242224Y269822D01*
X253103D01*
X253890Y269035D01*
Y267917D01*
G03Y265197I1469J-1360D01*
G01Y262357D01*
G02X253754Y262014I-500J0D01*
G03Y259264I1455J-1375D01*
G02X253890Y258921I-364J-343D01*
G01Y253873D01*
X255615Y252148D01*
X257646D01*
G02X258114Y251826I1J-500D01*
G01Y251825D01*
G03X259929Y250913I1404J533D01*
G02X260420Y250786I138J-481D01*
G01X262665Y248541D01*
Y244772D01*
X267740Y239697D01*
Y234482D01*
X269298Y232924D01*
X283855D01*
X298532Y218247D01*
X302018D01*
X332570Y187695D01*
Y124082D01*
X332342Y123805D01*
X332166Y123771D01*
G03X331064Y121726I287J-1474D01*
G01X331122Y121586D01*
X331062Y121289D01*
X326518Y116745D01*
X324779D01*
X323059Y115025D01*
Y106322D01*
X324626Y104755D01*
Y99495D01*
X324587Y99402D01*
G03Y98232I1383J-585D01*
G01X324626Y98139D01*
Y96235D01*
X324192Y95801D01*
G02X323630Y95701I-353J354D01*
G01X323629D01*
G03X321636Y93708I-629J-1364D01*
G01Y93707D01*
G02X321536Y93145I-454J-209D01*
G01X321002Y92611D01*
X321001D01*
X320708Y92318D01*
Y89963D01*
X320610Y89758D01*
X320521Y89687D01*
G03Y87347I942J-1170D01*
G01X320610Y87276D01*
X320708Y87071D01*
Y77887D01*
X320585Y77663D01*
X320476Y77594D01*
G03Y75060I807J-1267D01*
G01X320585Y74991D01*
X320708Y74767D01*
Y73354D01*
X320234Y72880D01*
X268963D01*
X266449Y75394D01*
Y80713D01*
X267640Y81904D01*
Y99920D01*
X265791Y101769D01*
Y106541D01*
X265840Y106590D01*
Y115310D01*
X263699Y117451D01*
X252326D01*
X250120Y119657D01*
Y134508D01*
X229152Y155476D01*
Y198426D01*
X223620Y203958D01*
Y230657D01*
X222170Y232107D01*
Y249873D01*
X225564Y253267D01*
X235454D01*
X238367Y256180D01*
G02X238931Y256279I353J-354D01*
G01X238932D01*
G03X240929Y258276I637J1360D01*
G01Y258277D01*
G02X241028Y258841I453J211D01*
G01X241096Y258909D01*
Y261570D01*
X240864Y261802D01*
Y262537D01*
X241531Y263204D01*
Y264359D01*
X241242Y264648D01*
X240899Y265102D01*
G02X240806Y265495I398J302D01*
G01X240817Y265556D01*
X241396Y266329D01*
X241069Y267460D01*
X240575Y268329D01*
X240586Y268534D01*
G03X241034Y269307I-1017J1106D01*
G37*
%LPD*%
G75*
G54D10*
X-294532Y1044846D03*
X-281332D03*
X-287932D03*
X-267012Y1044916D03*
X-39858Y731383D03*
X-31858D03*
X4390Y533777D03*
X13170Y372673D03*
X18340Y366452D03*
X13120Y375871D03*
X16010Y369168D03*
X21530Y368991D03*
X14140Y391826D03*
X18210Y386530D03*
X13950Y388616D03*
X13390Y397543D03*
X14240Y394866D03*
X19450Y550297D03*
X20650Y546243D03*
X20350Y555807D03*
X18960Y572061D03*
X17876Y578422D03*
X16200Y566921D03*
X17020Y592934D03*
X13510Y591939D03*
X15850Y610980D03*
X14500Y601957D03*
X11980Y617956D03*
X15349Y614142D03*
X14550Y628297D03*
X13807Y634826D03*
X9300Y631472D03*
X9240Y638699D03*
X11680Y656335D03*
X9260Y658321D03*
X14000Y658369D03*
X14170Y653991D03*
X9360Y653943D03*
X23987Y12977D03*
X36848Y25198D03*
X28408Y26414D03*
X30274Y37714D03*
X36588Y32278D03*
X36567Y73145D03*
X39126Y84631D03*
X34008Y91017D03*
X36567Y107988D03*
X32260Y96899D03*
X38280Y362184D03*
X35750Y364593D03*
X33420Y367309D03*
X23860Y366275D03*
X34140Y540345D03*
X34240Y536966D03*
X33231Y556346D03*
X30672Y551245D03*
X23610Y568111D03*
X28112Y591718D03*
X28270Y602194D03*
X33140Y602232D03*
X28185Y612088D03*
X30744Y617898D03*
X24168Y655750D03*
X37920Y651828D03*
X49890Y30392D03*
X51580Y17595D03*
X42205Y21518D03*
X54800Y25547D03*
X50981Y58681D03*
X46981Y58690D03*
X44010Y55170D03*
X54981Y59420D03*
X49559Y50577D03*
X41685Y73110D03*
X54101Y74252D03*
X51340Y69181D03*
X46570Y73891D03*
X47510Y109421D03*
X40690Y359555D03*
X53340Y393132D03*
X49750Y387305D03*
X51720Y384808D03*
X50840Y395761D03*
X47820Y398827D03*
X51670Y462885D03*
X47590Y463876D03*
X49830Y465496D03*
X47200Y467262D03*
X49590Y469432D03*
X49185Y472713D03*
X53769Y513033D03*
X54988Y518683D03*
X54117Y529098D03*
X49857Y520516D03*
X50630Y529281D03*
X41957Y543321D03*
X50140Y550572D03*
X39540Y538464D03*
X50870Y564008D03*
X43467Y555938D03*
X53988Y568748D03*
X49680Y579709D03*
X49620Y574212D03*
X47557Y588971D03*
X44507Y594082D03*
X40908Y589691D03*
X39360Y604593D03*
X39370Y600956D03*
X42950Y612487D03*
X50270Y627793D03*
X48540Y624953D03*
X52230Y614907D03*
X51051Y619407D03*
X48060Y621229D03*
X47480Y616848D03*
X51038Y643928D03*
X46890Y633564D03*
X53751Y652029D03*
X44640Y651029D03*
X40980Y656396D03*
X49720Y668412D03*
X56610Y20553D03*
X60318Y65593D03*
X64190Y72841D03*
X61760Y107321D03*
X55230Y112521D03*
X63900Y112081D03*
X64309Y141882D03*
X67853Y180744D03*
X68690Y175589D03*
X68930Y197193D03*
X66570Y189983D03*
X68830Y215817D03*
X56287Y242872D03*
X63718Y239030D03*
X61945Y267579D03*
X66818Y297483D03*
X57994Y287655D03*
X58000Y412641D03*
X64568Y451029D03*
X67568D03*
X70568D03*
X61357Y483392D03*
Y480892D03*
Y477892D03*
X61188Y487117D03*
X56330Y497940D03*
X58830D03*
X61676Y502656D03*
Y500156D03*
X61188Y489617D03*
Y492117D03*
X55982Y494543D03*
X64480Y501596D03*
X62253Y522589D03*
X67369Y522993D03*
X70696Y527237D03*
X57710Y572918D03*
X57070Y580074D03*
X57440Y585607D03*
X68630Y599945D03*
X61205Y623870D03*
X63570Y613914D03*
X63610Y618917D03*
X61205Y628870D03*
X62160Y644091D03*
X59390Y642906D03*
X56240Y630081D03*
X59530Y631704D03*
X63650Y646957D03*
X61600Y653611D03*
X66880Y761625D03*
X59260Y779815D03*
X58840Y783097D03*
X62290Y779629D03*
X67660Y779452D03*
X62730Y782694D03*
X66860Y782716D03*
X60370Y776861D03*
X64790Y776777D03*
X56500Y789667D03*
X76880Y126528D03*
X76030Y156152D03*
X85010Y171679D03*
X71510Y164548D03*
X74470Y175666D03*
X82553Y185431D03*
X86172Y213852D03*
X75560Y218513D03*
X73870Y205758D03*
X83390Y235665D03*
X79142Y237920D03*
X86479Y249259D03*
X77239Y260814D03*
X81165Y257717D03*
X78373Y276029D03*
X78220Y281745D03*
X78207Y279092D03*
X72190Y297395D03*
X82560Y288099D03*
X82600Y285426D03*
X77368Y299206D03*
X74058Y389621D03*
X83084D03*
X73868Y397913D03*
X83245D03*
X80490Y420690D03*
Y423690D03*
X86050Y428718D03*
X80490Y426690D03*
X79900Y439193D03*
X86050Y425112D03*
Y437470D03*
Y434470D03*
X79900Y445193D03*
Y442193D03*
X85617Y451275D03*
X82617D03*
X86050Y443432D03*
Y446432D03*
X74291Y486665D03*
X83536Y498308D03*
X81174Y503587D03*
X85346Y512295D03*
X73057Y515286D03*
X72635Y508991D03*
X81635Y521104D03*
X82031Y523928D03*
X84990Y563286D03*
X82140Y560758D03*
X81980Y556851D03*
X81516Y577905D03*
X83030Y582656D03*
X85140Y585213D03*
X75380Y608914D03*
Y603914D03*
X102257Y167955D03*
X90905Y199733D03*
X101449Y194368D03*
X98700Y234650D03*
X96990Y223043D03*
X101020Y223348D03*
X88399Y244041D03*
X95951Y376661D03*
X90031Y421693D03*
X90238Y418623D03*
X88617Y451275D03*
X86695Y498180D03*
X87721Y505817D03*
X92422Y531081D03*
X95660Y531362D03*
X98803Y531597D03*
X97268Y537055D03*
X97366Y542897D03*
X88200Y568111D03*
X98370Y619252D03*
X94070Y618986D03*
Y613841D03*
X97790Y613797D03*
X96200Y616325D03*
X95350Y644088D03*
X95310Y647481D03*
X98480Y646217D03*
X98410Y648878D03*
X89810Y765905D03*
X97390Y766435D03*
X98590Y782494D03*
X97180Y786472D03*
X111220Y160923D03*
X106090Y167615D03*
X112530Y186363D03*
X106760Y175370D03*
X114920Y179082D03*
X108910Y193194D03*
X104550Y262359D03*
X104270Y265662D03*
X110230Y360735D03*
X103151Y373340D03*
X110230Y363235D03*
X117030Y389978D03*
X103750Y402740D03*
X103810Y405876D03*
X103870Y399604D03*
X108235Y401017D03*
X111120Y401084D03*
X115727Y405844D03*
X113412Y404826D03*
X113504Y407673D03*
X107531Y394023D03*
X115516Y485696D03*
X117026Y488316D03*
X108026Y492500D03*
X109972Y509321D03*
Y519508D03*
X106358Y785790D03*
X102421Y782191D03*
X110295Y785734D03*
Y782191D03*
X116370Y785941D03*
X104300Y773100D03*
X106650Y779581D03*
X102421Y785938D03*
X130195Y19162D03*
X131068Y76588D03*
X126220Y80364D03*
Y83291D03*
X125480Y91163D03*
X132400Y88153D03*
X129580Y86837D03*
X129780Y92580D03*
X124150Y94643D03*
X128330Y98360D03*
X129650Y250414D03*
Y255414D03*
X130324Y272096D03*
Y277096D03*
X123960Y283696D03*
X128960D03*
X125050Y384546D03*
X122120Y386736D03*
X126300Y390369D03*
X129028Y425593D03*
X126377Y466738D03*
X126260Y470267D03*
X127705Y489431D03*
X125105D03*
X119326Y489706D03*
X121968Y488481D03*
X118124Y510811D03*
X133138Y510114D03*
X121644Y509398D03*
X130596Y510042D03*
X124652Y509398D03*
X130703Y512549D03*
X130844Y515128D03*
X128087Y513874D03*
X124279Y523691D03*
X120300Y572512D03*
X133590Y588438D03*
X130790Y595613D03*
X132190Y662616D03*
X121070Y670509D03*
X132050Y671817D03*
X133607Y686699D03*
X130260Y679836D03*
X132438Y704733D03*
X133490Y695470D03*
X126220Y720949D03*
X132334Y732982D03*
X119900Y754021D03*
X125600Y759000D03*
X125960Y785699D03*
X120090Y780618D03*
X130850Y782456D03*
X118169Y783857D03*
X130660Y785601D03*
X127290Y781982D03*
X122720Y785051D03*
X141490Y19267D03*
X137872Y29551D03*
X147427Y30367D03*
X146380Y20345D03*
X139931Y40842D03*
X139932Y35310D03*
X135050Y53493D03*
X137540Y58255D03*
X143857Y51943D03*
X149025Y51720D03*
X135290Y87664D03*
X140350Y81347D03*
X144400Y244061D03*
Y247561D03*
X148330Y258806D03*
X145200Y276468D03*
X138930Y278965D03*
X148350Y281769D03*
X134540Y267786D03*
X137990Y296735D03*
X139950Y293835D03*
X149020Y303498D03*
X145720Y311336D03*
X146100Y323543D03*
X145580Y316836D03*
X137889Y403348D03*
X141800Y404481D03*
X141847Y401820D03*
X135088Y405060D03*
X135181Y402121D03*
X145295Y404388D03*
X145284Y401507D03*
X142239Y422346D03*
X139395Y425090D03*
X138437Y435930D03*
Y438430D03*
X147576Y445279D03*
Y447779D03*
Y450279D03*
X138437Y440930D03*
X135300Y468444D03*
X146240Y472111D03*
X139310Y478102D03*
X136470Y481994D03*
X149477Y532733D03*
X144120Y547577D03*
X146920Y547677D03*
X143252Y573105D03*
X145550Y588088D03*
X149050Y588044D03*
X141260Y588175D03*
X136420Y599352D03*
X148140Y660112D03*
X148487Y676041D03*
X148200Y669205D03*
X140110Y675907D03*
X139158Y686725D03*
X135280Y679212D03*
X138726Y696707D03*
X138198Y712628D03*
X144631Y735955D03*
X147290Y744113D03*
X145040Y740741D03*
X139600Y781281D03*
X135470Y781697D03*
X135610Y784521D03*
X139680Y784596D03*
X149450Y780429D03*
X146150Y783820D03*
X145570Y780580D03*
X157877Y30674D03*
X152810Y29921D03*
X158165Y21300D03*
X150592Y20974D03*
X156255Y45743D03*
X159861Y36134D03*
X160731Y41038D03*
X162350Y42984D03*
X157659Y47891D03*
X157010Y58963D03*
X164550Y61239D03*
X156440Y74863D03*
X151618Y83343D03*
X164280Y101810D03*
X164490Y127110D03*
X159190Y127781D03*
X152990Y248096D03*
X157690Y249918D03*
X154546Y256986D03*
X152634Y276809D03*
X149721Y292987D03*
X152733Y288517D03*
X158076Y290635D03*
X154581Y308767D03*
X151230Y330164D03*
X150918Y318134D03*
X150510Y336306D03*
X156448Y336629D03*
X162071Y336947D03*
X165290Y385948D03*
X151820Y385554D03*
X150902Y379714D03*
X160886Y380294D03*
X160710Y384044D03*
X162940Y406188D03*
X154370Y449930D03*
X151145Y469456D03*
X150547Y459363D03*
X163377Y484538D03*
X152554Y494027D03*
X158406Y500016D03*
X162335Y512456D03*
X159196Y515612D03*
X159179Y521893D03*
X154126Y524411D03*
X154475Y530422D03*
X159180Y528227D03*
X162335Y543954D03*
X159185Y537654D03*
X162336Y550253D03*
X164259Y557273D03*
X154140Y577815D03*
X161280Y581585D03*
X162786Y568599D03*
X156480Y583315D03*
X153527Y597138D03*
X160699Y587904D03*
X150380Y602885D03*
X153712Y610917D03*
X153330Y599935D03*
X153422Y603043D03*
X153955Y620760D03*
X157963Y633735D03*
X162668Y631897D03*
X162530Y643235D03*
Y636435D03*
X151915Y675068D03*
X155957Y674813D03*
X160112Y674990D03*
X165012Y675887D03*
X164812Y662579D03*
X151567Y687579D03*
X155650Y681515D03*
X161994Y678445D03*
X159590Y683050D03*
X157287Y678138D03*
X165167Y681311D03*
X152222Y678394D03*
X160101Y687962D03*
X163018Y684381D03*
X164092Y688014D03*
X150840Y682436D03*
X154970Y736966D03*
X161981Y730784D03*
X158881D03*
X162640Y743927D03*
X158970D03*
X154400Y744337D03*
X155230Y740259D03*
X163138Y778565D03*
X160480Y777583D03*
X155170Y780656D03*
X164630Y781222D03*
X153320Y783499D03*
X160320Y786346D03*
X149810Y783858D03*
X168961Y27073D03*
X165959Y27133D03*
X173110Y26877D03*
X180907Y27544D03*
X176090Y26906D03*
X180159Y40661D03*
X165336Y46126D03*
X168040Y61462D03*
X177733Y91967D03*
X167383Y93147D03*
X168850Y99251D03*
X169510Y106579D03*
X173900Y97662D03*
X177680Y101764D03*
X174710Y105699D03*
X177763Y121057D03*
X168170Y123367D03*
X173170D03*
X178040Y228978D03*
X167483Y239914D03*
X177891Y249324D03*
X175756Y257668D03*
X173263Y262589D03*
X176301Y262624D03*
X167322Y255855D03*
X167698Y260617D03*
X178929Y262244D03*
X175110Y260412D03*
X178025Y279018D03*
X174078Y271435D03*
X170829Y271452D03*
X178941Y270160D03*
X178810Y287263D03*
X174148Y289289D03*
X175921Y301920D03*
X178921D03*
X178660Y388418D03*
X171934Y386364D03*
X175155Y380727D03*
X180430Y392969D03*
X175663Y386424D03*
X176371Y404721D03*
X180440Y398056D03*
X172760Y406540D03*
X167527Y420268D03*
X179562Y424001D03*
X173381Y424005D03*
X170683Y436834D03*
X170361Y428595D03*
X177525Y451946D03*
X180125D03*
X178961Y448138D03*
X176220Y448247D03*
X171616Y467804D03*
X168370Y477790D03*
X169728Y487664D03*
X168189Y514331D03*
X178085Y512456D03*
X173252Y515693D03*
X165707Y506156D03*
X172087Y510536D03*
X169615Y519216D03*
X178094Y531365D03*
X166297Y532416D03*
X169491Y529702D03*
X166837Y523486D03*
X174395Y527975D03*
X171606Y527511D03*
X168243Y542706D03*
X174930Y547106D03*
X169157Y548676D03*
X173163Y551903D03*
X169444Y558757D03*
X167105Y552882D03*
X178083Y553402D03*
X172889Y562710D03*
X175330Y578535D03*
X166930Y578435D03*
X166786Y569056D03*
X175386Y569589D03*
X179740Y568951D03*
X172430Y584035D03*
X177830Y583535D03*
X166570Y583874D03*
X166605Y587860D03*
X178416Y587849D03*
X179120Y639615D03*
X169930Y635329D03*
X172510Y639771D03*
X167530Y631935D03*
X174479Y631986D03*
X167810Y668131D03*
X168645Y688064D03*
X165628Y691289D03*
X167315Y684943D03*
X178982Y688631D03*
X171180Y683815D03*
X169268Y705304D03*
X169396Y701006D03*
X169268Y697399D03*
X169619Y693335D03*
X180820Y717914D03*
X171154Y715673D03*
X169531Y710542D03*
X175463Y720245D03*
X165599Y730476D03*
X174954Y728404D03*
X177920Y739302D03*
X167568Y743335D03*
X177224Y777765D03*
X169350Y785470D03*
X172600Y780150D03*
X169860Y782086D03*
X167350Y778074D03*
X194825Y10196D03*
X194861Y12952D03*
X183407Y27544D03*
X188634Y27860D03*
X191596Y27620D03*
X184928Y91847D03*
X189928D03*
X196653Y91837D03*
X196493Y105637D03*
X183013Y98813D03*
X190100Y99701D03*
X188203Y104567D03*
X194463Y122631D03*
X184050Y230139D03*
X183550Y235060D03*
X188899Y240208D03*
X195126Y249955D03*
X184296Y241098D03*
X188899Y236808D03*
X181176Y257643D03*
X188658Y256870D03*
X184117Y264852D03*
X181602Y262656D03*
X186873Y263697D03*
X185798Y256760D03*
X186873Y260697D03*
X194693Y259197D03*
Y262197D03*
X188418Y278887D03*
X183440Y269816D03*
X194205Y271034D03*
X191860Y270148D03*
X183198Y278034D03*
X191054Y294424D03*
X183254Y295023D03*
X192298Y286183D03*
X181921Y301920D03*
X191949Y301987D03*
X188810Y301998D03*
X187907Y308784D03*
X186254Y310663D03*
X183254D03*
X186350Y317116D03*
X196476Y317042D03*
X183228Y317023D03*
X193957Y317064D03*
X191159Y317171D03*
X190557Y325701D03*
X192230Y337322D03*
X192040Y333606D03*
X195420Y372406D03*
X184927Y383876D03*
X192681Y377554D03*
X193590Y383383D03*
X185074Y380726D03*
X196273Y403152D03*
X182132Y418327D03*
X192527Y429049D03*
X189077Y438281D03*
X184523Y441915D03*
X181923Y445044D03*
Y442544D03*
X193500Y489796D03*
X181231Y512455D03*
X184843Y533995D03*
X188640Y530667D03*
X191457Y531553D03*
X193466Y546886D03*
X186841Y545372D03*
X181232Y553402D03*
X181491Y557436D03*
X193080Y581235D03*
X191500Y571956D03*
X182480Y566819D03*
X196740Y589735D03*
X181330Y587535D03*
X192130Y632235D03*
X184748Y639687D03*
X182480Y634585D03*
X191480Y639135D03*
X182353Y631612D03*
X196410Y650155D03*
X187410Y649715D03*
Y659705D03*
X191910Y650055D03*
X185993Y682670D03*
X191542Y691925D03*
X181744Y694829D03*
X181950Y698191D03*
X190375Y695624D03*
X188566Y722353D03*
X183566D03*
X193566Y722333D03*
X196079Y723943D03*
X191150Y724108D03*
X186164Y724134D03*
X192949Y771020D03*
X182500Y780786D03*
X189770Y778082D03*
X204785Y13762D03*
X204978Y10605D03*
X201849Y15292D03*
X198577Y15374D03*
X204003Y91247D03*
X200480Y97687D03*
X212423Y104957D03*
X208908Y96975D03*
X205903Y101477D03*
X199993Y103637D03*
X210623Y121267D03*
X205535Y234497D03*
Y228682D03*
X211935Y230585D03*
X198296Y232699D03*
X211935Y237385D03*
Y240785D03*
X205566Y243497D03*
X205271Y240209D03*
X198685Y237385D03*
Y244085D03*
X210305Y259330D03*
Y262289D03*
X201994Y261248D03*
X200977Y256305D03*
X202402Y263713D03*
X200469Y259139D03*
X201518Y265990D03*
X209449Y281098D03*
X210303Y268227D03*
X206299Y281098D03*
X210303Y271227D03*
X203149Y281098D03*
X201518Y268887D03*
X209449Y287398D03*
Y290548D03*
X203149Y287398D03*
X206299D03*
X196867Y294342D03*
X206299Y290548D03*
X206319Y296863D03*
X203149Y290548D03*
X206299Y293698D03*
X198880Y310245D03*
X196812Y308619D03*
X206299Y306298D03*
Y303148D03*
X209449Y312598D03*
X203166Y312577D03*
X202525Y299358D03*
X206299Y315748D03*
X203058Y315593D03*
X200211Y321446D03*
X200572Y323920D03*
X208000Y325200D03*
X208700Y328000D03*
X200590Y327615D03*
X197938Y376839D03*
X206973Y361900D03*
X205790Y387003D03*
X201267Y403294D03*
X210880Y402359D03*
X206380Y402201D03*
X204584Y462478D03*
X197161Y465628D03*
X200459Y487253D03*
X211609Y516553D03*
X205257Y528822D03*
X211287Y528547D03*
X212342Y536729D03*
X199539Y537112D03*
X204309Y539953D03*
X205286Y551130D03*
X202486D03*
X211240Y572893D03*
X210040Y576893D03*
X201510Y576885D03*
X197730Y572893D03*
X197709Y567464D03*
X209590Y580893D03*
X210790Y566926D03*
X209940Y584893D03*
X197230Y595335D03*
X198890Y584105D03*
X207178Y591595D03*
X196907Y605012D03*
X197030Y598535D03*
X204024Y604135D03*
Y609135D03*
X208904Y611515D03*
X200380Y629085D03*
X199786Y618893D03*
X202510Y624005D03*
X197230Y615435D03*
X197130Y626135D03*
X208904Y616515D03*
X197480Y639815D03*
X203065Y638700D03*
X205221Y630886D03*
X200910Y659735D03*
Y650155D03*
X205410Y650035D03*
X199510Y663158D03*
X205410Y661200D03*
X211560Y670575D03*
X202518Y673273D03*
X197889Y671226D03*
X210824Y692266D03*
X199590Y682868D03*
X197582Y703474D03*
X200692Y704081D03*
X199350Y692724D03*
X211236Y695586D03*
X197243Y697899D03*
X198566Y722353D03*
X209017Y722344D03*
X203611Y722303D03*
X205440Y712510D03*
X211897Y723870D03*
X201411Y708231D03*
X205883Y724373D03*
X200817Y724180D03*
X199760Y763929D03*
X202050Y784919D03*
X206210Y771577D03*
X212350Y773283D03*
X222290Y45504D03*
X226290D03*
X221310Y51103D03*
X225310D03*
X215773Y90147D03*
X222983Y91587D03*
X220200Y93561D03*
X226620Y89385D03*
X214320Y101978D03*
X220983Y106174D03*
X213908Y96975D03*
X219510Y101338D03*
X228138Y125802D03*
X226010Y233542D03*
X217135Y230585D03*
X226010Y240342D03*
X217135Y240785D03*
Y237385D03*
X216512Y258490D03*
X225973Y262197D03*
X216109Y265139D03*
Y262139D03*
X218508Y256664D03*
X225973Y265197D03*
Y259197D03*
X218899Y281098D03*
X224357Y273228D03*
X216109Y271139D03*
X215749Y281098D03*
X213138Y274187D03*
X225160Y293676D03*
X225199Y290548D03*
Y284248D03*
X222049Y287398D03*
X212599D03*
X215749Y290548D03*
Y293698D03*
Y287398D03*
X225199Y306298D03*
Y312598D03*
X222049Y306298D03*
X218899D03*
X222049Y299998D03*
X212610Y306305D03*
X218899Y299998D03*
Y303148D03*
X218947Y312617D03*
X224949Y328707D03*
X225199Y315748D03*
X224585Y322992D03*
X224711Y325922D03*
X223166Y338842D03*
X222911Y333155D03*
X224996Y334617D03*
X223095Y336241D03*
X221280Y340579D03*
X222974Y356134D03*
X214657Y356205D03*
X214007Y362701D03*
X222225Y364031D03*
X227745Y368007D03*
X224108Y388029D03*
X214786Y388603D03*
X218090Y390891D03*
X216633Y384989D03*
X215120Y399654D03*
X214406Y395539D03*
X223085Y401702D03*
X213710Y402237D03*
X224730Y418003D03*
X221406Y436560D03*
X227816Y442675D03*
X218483Y442550D03*
X221858Y442300D03*
X225024Y442467D03*
X228242Y463681D03*
X223953Y463550D03*
X212809Y479053D03*
X215409Y479253D03*
X222419Y479933D03*
X218040Y473853D03*
X223786Y476638D03*
X226255Y472579D03*
X219309Y489353D03*
X222209D03*
X227284Y502591D03*
X224209Y491853D03*
X217609Y516353D03*
X219328Y528823D03*
X223376Y523322D03*
X215946Y544202D03*
X218950Y565589D03*
X227100Y580916D03*
X225100Y597453D03*
X219960Y596373D03*
Y601373D03*
X215604Y621977D03*
X228290Y629893D03*
X218308Y635939D03*
X225179Y642614D03*
X218240Y674433D03*
X225237Y671772D03*
X212635Y665604D03*
X224060Y690317D03*
X224336Y687758D03*
X223707Y695436D03*
X220580Y692876D03*
X223741Y700554D03*
X221340Y697995D03*
X217530Y715305D03*
X221320Y720698D03*
X213310Y719064D03*
X222710Y713706D03*
X216820Y723301D03*
X227650Y720791D03*
X224410Y719970D03*
X225940Y733671D03*
Y736437D03*
X218270Y785657D03*
X220960Y778561D03*
X226670Y773299D03*
X242290Y45504D03*
X230290D03*
X229310Y51103D03*
X233290Y51045D03*
X237310Y50983D03*
X241310D03*
X235113Y91307D03*
X231013Y91547D03*
X243373Y88767D03*
X239563Y92077D03*
X230643Y108497D03*
X234243Y100156D03*
X233083Y94817D03*
X237773Y103607D03*
X242913Y106157D03*
X233138Y125802D03*
X232948Y234047D03*
X236710Y244042D03*
X242460Y237591D03*
X237654Y249719D03*
X231710Y243642D03*
Y240242D03*
X239569Y257639D03*
X241613Y262197D03*
X239569Y266639D03*
X241613Y259197D03*
X237594Y252754D03*
X233793Y266697D03*
Y257697D03*
X239569Y263639D03*
X233793Y263697D03*
X231749Y262139D03*
X233793Y260697D03*
X239569Y260639D03*
X231749Y259139D03*
X234649Y281098D03*
X237865Y281131D03*
X239569Y269639D03*
X232118Y271587D03*
X241613Y271197D03*
Y268197D03*
X228821Y274197D03*
X231648Y274243D03*
X231450Y290583D03*
X237760Y293692D03*
X237799Y287398D03*
X240949Y290548D03*
Y287398D03*
X231499Y284248D03*
Y296848D03*
Y293698D03*
X240949Y296848D03*
X231499Y299998D03*
X237799Y312598D03*
X231499D03*
X240949Y309448D03*
X237799Y303148D03*
X234649D03*
X237799Y306298D03*
X240925Y306257D03*
X240949Y299998D03*
Y303148D03*
X231567Y321742D03*
X232782Y327096D03*
X230725Y325649D03*
X238545Y327149D03*
X240374Y328960D03*
X240511Y325517D03*
X238548Y333149D03*
X230725Y334547D03*
X240598Y334642D03*
X240218Y338010D03*
X231144Y338225D03*
X238560Y336136D03*
X232769Y333207D03*
X232804Y336181D03*
X239290Y340428D03*
X228419Y356855D03*
X233635Y357082D03*
X230010Y373300D03*
X237578Y369584D03*
X233136Y367070D03*
X243078Y368384D03*
X231257Y362218D03*
X228729Y385227D03*
X241451Y392147D03*
X236412Y387722D03*
X231223Y391424D03*
X239546Y390528D03*
X239228Y393291D03*
X236430Y393470D03*
X232647Y396011D03*
X228906Y424560D03*
X228713Y416525D03*
Y419525D03*
X231870Y439511D03*
X228906Y433560D03*
Y427560D03*
Y436560D03*
X231885Y442252D03*
X235319Y464362D03*
X231461Y462591D03*
X243471Y460292D03*
X238430Y460338D03*
X233309Y472553D03*
X237609Y472453D03*
X241909Y472553D03*
X234209Y480953D03*
X228604Y479682D03*
X233626Y512040D03*
X236776Y534087D03*
X233626Y524639D03*
X236776Y540386D03*
X235307Y566357D03*
X243209Y574018D03*
X229269Y597682D03*
X242830Y597415D03*
X234370Y593242D03*
X242796Y589749D03*
X236780Y628738D03*
X229199Y642180D03*
X243693Y632254D03*
X238420Y642148D03*
X234500Y637685D03*
X243743Y636514D03*
X241670Y652558D03*
X233584Y652519D03*
X239168Y671672D03*
X237275Y679609D03*
X239084Y696252D03*
X233954Y697395D03*
X236120Y704173D03*
X242680Y712337D03*
X234960Y714064D03*
X239210Y720040D03*
X234910Y720816D03*
X234940Y733355D03*
X243940Y736412D03*
X239500Y733523D03*
X230440Y724242D03*
X234940Y736392D03*
X236180Y786517D03*
X242230Y774803D03*
X234011Y772902D03*
X250290Y45504D03*
X246290D03*
X258103Y53688D03*
X257500Y56117D03*
X245310Y50867D03*
X249300Y50862D03*
X253490Y53736D03*
X252683Y105867D03*
X253558Y95038D03*
X256133Y99347D03*
X248558Y95038D03*
X259030Y123727D03*
X259443Y120773D03*
X249453Y114307D03*
X255287Y226709D03*
X254221Y230582D03*
X256492Y222466D03*
X254181Y234521D03*
X257950Y236924D03*
X254418Y240407D03*
X247389Y259139D03*
X256553Y256881D03*
X249433Y263697D03*
Y260697D03*
X256916Y262609D03*
X247389Y262139D03*
X257253Y259197D03*
X259518Y252358D03*
X244099Y281098D03*
X254234Y281622D03*
X250399Y281098D03*
X247389Y268139D03*
X257253Y271197D03*
Y268197D03*
X244110Y290505D03*
X257447Y287117D03*
X244099Y287398D03*
X250399D03*
X253549Y290548D03*
X247249Y296848D03*
X244099D03*
X258380Y295984D03*
X254007Y306819D03*
X244118Y303187D03*
X257057Y309636D03*
X244099Y299998D03*
X247249Y306298D03*
X257418Y303533D03*
X258590Y311560D03*
X247290Y327694D03*
X254631Y324716D03*
X254998Y329779D03*
X256276Y322652D03*
X247789Y322910D03*
X254905Y327213D03*
X250401Y315713D03*
X253710Y315669D03*
X246685Y337357D03*
X255124Y335244D03*
X247025Y330512D03*
X251491Y357134D03*
X256588Y359005D03*
X244595Y363535D03*
X256532Y384895D03*
X247065Y385398D03*
X244546Y385315D03*
X253762Y385255D03*
X247797Y406029D03*
X250297D03*
X252797D03*
X245297D03*
X258798Y417594D03*
X254798Y417728D03*
X254813Y427018D03*
X252670Y443592D03*
X246465Y464893D03*
X251780Y460883D03*
X257568Y461513D03*
X255509Y472253D03*
X246109Y472465D03*
X251309Y472553D03*
X252036Y582131D03*
X245860Y575049D03*
X249909Y568653D03*
X259678Y581553D03*
X253187Y596382D03*
X249013Y628514D03*
X251803Y636704D03*
X254773Y644424D03*
X254303Y636744D03*
X256463Y639364D03*
X252173Y644344D03*
X249083Y636664D03*
X256513Y642494D03*
X246553Y636684D03*
X252486Y671772D03*
X244780Y682521D03*
X250795Y703150D03*
X251451Y697465D03*
X259170Y705138D03*
X258570Y722981D03*
X255310Y715915D03*
X248530Y721829D03*
X250630Y719457D03*
X248770Y724631D03*
X252940Y733567D03*
X256650Y778342D03*
X247900Y778823D03*
X252470Y785797D03*
X262955Y12663D03*
X266111Y29229D03*
X265789Y20990D03*
X268809Y16400D03*
X274990Y16396D03*
X272010Y40553D03*
X274510D03*
X267703Y89397D03*
X272245Y89585D03*
X263703Y93847D03*
X271133Y92787D03*
X265830Y102566D03*
X273973Y97645D03*
X262473Y106937D03*
X263683Y99902D03*
X269010Y121648D03*
X264980Y121886D03*
X269192Y248209D03*
X272242Y244842D03*
X272620Y238653D03*
X260108Y240376D03*
X267118Y245587D03*
X271458Y241347D03*
X270260Y237037D03*
X266187Y249852D03*
X273521Y265849D03*
X260068Y262187D03*
X263268Y262370D03*
X263774Y256464D03*
X272464Y259964D03*
X269263Y252800D03*
X263029Y271139D03*
Y268139D03*
X273444Y270543D03*
X274944Y278363D03*
X270386Y280407D03*
X267386D03*
Y296047D03*
X261463Y296111D03*
X265825Y293987D03*
X268867Y293942D03*
X270444Y286183D03*
X265768Y287546D03*
X273444Y286183D03*
X273618Y295387D03*
X260045Y309615D03*
X268944Y309643D03*
X265944Y309640D03*
X261915Y302033D03*
X269380Y302736D03*
X264501Y303109D03*
X266939Y303281D03*
X274303Y303413D03*
X259820Y303800D03*
X267268Y311642D03*
X264287Y311687D03*
X270518Y311637D03*
X274832Y309687D03*
X265318Y326487D03*
X270525Y325754D03*
X262201Y328491D03*
X272967Y325842D03*
X275517D03*
X267030Y330147D03*
X262700Y325494D03*
X270485Y339030D03*
X264015Y336151D03*
X263173Y331794D03*
X267943Y339617D03*
X270293Y330540D03*
X272964Y330669D03*
X262379Y338103D03*
X262247Y334502D03*
X270071Y333021D03*
X272263Y334222D03*
X272352Y340900D03*
X269456Y355353D03*
X269886Y358753D03*
X260536Y374216D03*
X270293Y363972D03*
X273477Y385100D03*
X261663Y385193D03*
X267993Y390695D03*
X270796Y386643D03*
X266882Y388165D03*
X261539Y387755D03*
X264421Y384812D03*
X275497Y390758D03*
X263419Y393450D03*
X265162Y401391D03*
X272220Y401343D03*
X271720Y422587D03*
X265532Y422648D03*
X269630Y424884D03*
X274180Y424966D03*
X266822Y443297D03*
X275256Y445753D03*
X271035Y443051D03*
X273735Y443034D03*
X273509Y471649D03*
X263807Y461234D03*
X260609Y472453D03*
X264909Y472553D03*
X269109Y472353D03*
X275452Y483219D03*
X263924Y491754D03*
X269609Y576413D03*
X274309Y574653D03*
X261175Y569054D03*
X263792Y574203D03*
X268009Y570953D03*
X273480Y589201D03*
X269609Y588653D03*
X268717Y606015D03*
X261967Y608638D03*
Y605638D03*
X260064Y602993D03*
X261967Y614638D03*
X263467Y626638D03*
X269428Y622966D03*
X261967Y617638D03*
X263467Y623638D03*
X273938Y633084D03*
X273674Y640095D03*
X273548Y636471D03*
X266610Y654171D03*
X270040Y651241D03*
X269640Y655290D03*
X265913Y671772D03*
X261890Y664761D03*
X265550Y668415D03*
X274360Y673831D03*
X272460Y687889D03*
X267240Y682519D03*
X269420Y677062D03*
X272650Y693742D03*
X269410Y706003D03*
X267124Y707892D03*
X273510Y699749D03*
X266170Y694826D03*
X260680Y712988D03*
X271210Y718000D03*
X264600Y723086D03*
X270940Y722080D03*
X263430Y770417D03*
X264340Y778780D03*
X272175Y783074D03*
X278660Y10073D03*
X284505Y30676D03*
X287766Y21289D03*
X277472Y34959D03*
Y37459D03*
X280072Y34330D03*
X275766Y52772D03*
X275800Y50212D03*
X277000Y88323D03*
X286263Y88677D03*
X276603Y92119D03*
X287423Y91857D03*
X287595Y106109D03*
X279010Y104889D03*
X286710Y95717D03*
X281200Y98369D03*
X289720Y96094D03*
X278760Y101061D03*
X279161Y237817D03*
X276904Y252550D03*
X282166Y262922D03*
X281945Y260231D03*
X278811Y259135D03*
X279336Y264795D03*
X276444Y270543D03*
X282309Y270435D03*
X279444Y270543D03*
X277944Y278363D03*
X279386Y280407D03*
X276386D03*
X281767Y277742D03*
X290363Y286082D03*
X286132Y285953D03*
X281818Y290787D03*
X278918Y286887D03*
X276444Y286183D03*
X277020Y302298D03*
X282337Y308217D03*
X281859Y310862D03*
X277816Y309678D03*
X279754Y303269D03*
X276386Y311687D03*
X286071Y329184D03*
X278067Y325842D03*
X282167Y324242D03*
X288466Y325343D03*
X285704Y321809D03*
X277288Y334282D03*
X282234Y333792D03*
X285794Y339063D03*
X281205Y340997D03*
X279718Y333694D03*
X275602Y343811D03*
X289191Y341348D03*
X286020Y356454D03*
X277040Y376172D03*
X279863Y367513D03*
X286550Y374402D03*
X281450Y373151D03*
X288687Y385290D03*
X281864Y386178D03*
X284687Y386769D03*
X285390Y390550D03*
X288220Y389630D03*
X287067Y402358D03*
X280730Y393856D03*
X276400Y422341D03*
X280010Y422279D03*
X281190Y424966D03*
X278080Y424760D03*
X286210Y444926D03*
X289630Y444828D03*
X283212Y442286D03*
X286100Y442298D03*
X288742Y442090D03*
X287970Y446705D03*
X282000Y444966D03*
X279112Y444954D03*
X276626Y442913D03*
X279990Y442071D03*
X280210Y460762D03*
X287567Y470649D03*
Y467649D03*
X280380Y467284D03*
X278990Y464793D03*
X277470Y481197D03*
X280970D03*
X288009Y495653D03*
X284024Y502595D03*
X290323D03*
X280874Y556139D03*
X279658Y574443D03*
X285530Y573002D03*
X283650Y589044D03*
X278109Y589238D03*
X287997Y649064D03*
X280880Y650295D03*
X278699Y656491D03*
X279090Y668504D03*
X279785Y663876D03*
X289365Y665845D03*
Y673719D03*
X279843Y675688D03*
X278350Y687309D03*
X275710Y681593D03*
X289248Y680521D03*
X275560Y697804D03*
X279060Y693306D03*
X284760Y707022D03*
X286798Y704143D03*
X278370Y705093D03*
X277475Y695723D03*
X289060Y722193D03*
X281830Y722184D03*
X285130Y714433D03*
X275880Y722141D03*
X285880Y722268D03*
X289150Y718548D03*
X280210Y734805D03*
X288390Y734796D03*
X284020Y724956D03*
X284532Y747493D03*
X275627Y777692D03*
X281930Y773190D03*
X286722Y785929D03*
X296093Y88477D03*
X302853Y89057D03*
X301870Y92072D03*
X296870D03*
X294800Y100593D03*
X295490Y97209D03*
X302370Y95215D03*
X291927Y102991D03*
X293505Y94965D03*
X296927Y102991D03*
X303220Y98397D03*
X293873Y130357D03*
X302930Y132994D03*
X296176Y249585D03*
X299776Y248010D03*
X301511Y262204D03*
X300477Y265010D03*
X296210Y253187D03*
X300310Y253842D03*
Y257242D03*
X292710Y266542D03*
X301473Y282650D03*
X297810Y280709D03*
X301723Y279150D03*
X301182Y291966D03*
X294382D03*
X305132Y286867D03*
X298332D03*
X301732D03*
X301795Y310398D03*
X296639Y308057D03*
X305250Y310342D03*
X300201Y300874D03*
X303197Y304297D03*
X297073Y329159D03*
X298452Y340487D03*
X305880Y339046D03*
X306820Y342146D03*
X299410Y331201D03*
X303759Y331478D03*
X305446Y359450D03*
X295527Y359812D03*
X303171Y374224D03*
X291686Y375177D03*
X295388Y375644D03*
X293290Y389737D03*
X291382Y385457D03*
X299533Y394056D03*
X291860Y442927D03*
X292170Y445986D03*
X300040Y459733D03*
X303631Y475607D03*
Y472607D03*
X297370Y498563D03*
X300209Y495853D03*
X305708Y503043D03*
X295047Y554565D03*
X304410Y572782D03*
X306229Y600263D03*
X301796Y603917D03*
X298303Y613184D03*
X302870Y633981D03*
X297162Y642065D03*
X293843Y642536D03*
X303110Y639381D03*
X301070Y655920D03*
X292850Y656359D03*
X304870Y655747D03*
X306294Y659156D03*
X297394Y657033D03*
X302772Y659604D03*
X301360Y652183D03*
X306294Y667156D03*
Y663156D03*
Y675156D03*
Y671156D03*
X300880Y664296D03*
X294120Y668391D03*
X295890Y662662D03*
X297770Y674720D03*
X305979Y691156D03*
X306145Y683156D03*
X305979Y687156D03*
X306294Y679156D03*
X292970Y682450D03*
X295950Y689520D03*
X293068Y677108D03*
X296858Y702544D03*
X297300Y697221D03*
X293286Y703504D03*
X305990Y697189D03*
X303681Y714421D03*
X305213Y720393D03*
X293300Y718944D03*
X296885Y718059D03*
X297223Y715523D03*
X291318Y713875D03*
X302810Y733807D03*
X298590Y733669D03*
X293480Y725080D03*
X295700Y733133D03*
X293440Y748380D03*
X291340Y771217D03*
X295100Y786269D03*
X299249Y771403D03*
X304740Y777277D03*
X317334Y10955D03*
X322640Y9774D03*
X317334Y28955D03*
X321283Y76327D03*
X314830Y92851D03*
X312183Y88837D03*
X321463Y88517D03*
X315083Y90207D03*
X311553Y92347D03*
X310850Y99620D03*
X320740Y98599D03*
X312223Y96407D03*
X317970Y95961D03*
X311290Y247249D03*
X312680Y258353D03*
X307204Y304212D03*
X310623Y313589D03*
X313123D03*
X320623D03*
X318123D03*
X315623D03*
X311740Y325839D03*
X313980Y335813D03*
X314550Y331564D03*
X318480Y335039D03*
X321130Y342418D03*
X309190Y336959D03*
X319807Y346376D03*
X321150Y357730D03*
X319288Y350376D03*
X307410Y348380D03*
X313222Y374229D03*
X322255Y371935D03*
X321297Y367739D03*
X319363Y372149D03*
X310484Y383312D03*
X321144Y399643D03*
X318644D03*
X316190Y413299D03*
X317140Y421775D03*
X321910Y410139D03*
X311610Y432528D03*
X313530Y436460D03*
X315940Y438104D03*
X319478Y429389D03*
X308220Y432552D03*
X322599Y432505D03*
X309440Y426404D03*
X318950Y432473D03*
X321357Y456709D03*
X307800Y467859D03*
X310380Y473942D03*
X321246Y472669D03*
X315980Y472128D03*
X307670Y473605D03*
X320080Y512736D03*
X318678Y540966D03*
X321828Y541682D03*
X313419Y594040D03*
X313227Y590232D03*
X310919Y594040D03*
X310627Y590232D03*
X315957Y594127D03*
X320094Y604114D03*
X320512Y613603D03*
X308741Y623871D03*
X311311Y618197D03*
X317492Y618193D03*
X314940Y642067D03*
X310453Y642451D03*
X320360Y642275D03*
X311382Y635432D03*
X316184Y662630D03*
X314614Y690767D03*
X316184Y687630D03*
X316165Y693404D03*
X313230Y702465D03*
X307113Y713003D03*
X321820Y712680D03*
X311990Y717601D03*
X319620Y716403D03*
X309531Y714298D03*
X312972Y712693D03*
X318090Y712846D03*
X307280Y733705D03*
X321930Y724895D03*
X314930Y724533D03*
X307146Y769416D03*
X315020Y780559D03*
X320657Y779595D03*
X320440Y771967D03*
X323334Y12377D03*
X323871Y25812D03*
Y16812D03*
Y19812D03*
Y28812D03*
X327117Y31840D03*
X323640Y74393D03*
X326140Y76196D03*
X335668Y92822D03*
X330668D03*
X325360Y92517D03*
X324070Y88861D03*
X323000Y94337D03*
X325970Y98817D03*
X327430Y108208D03*
X327190Y103818D03*
X337630Y106304D03*
X334720Y102184D03*
X332453Y122297D03*
X331583Y128717D03*
X336495Y290569D03*
X328526Y308696D03*
X334478Y299604D03*
X323123Y313589D03*
X336720Y310846D03*
X337293Y316660D03*
X333540Y315590D03*
X333726Y353801D03*
X333440Y349221D03*
X327058Y358376D03*
X323040Y354485D03*
X336850Y380332D03*
X326282Y399743D03*
X323644Y399643D03*
X331090Y424304D03*
X331900Y419317D03*
X336740Y417069D03*
X328290Y424304D03*
X324940Y413899D03*
X334420Y428660D03*
X326190Y448621D03*
X329120Y449203D03*
X327780Y445819D03*
X331360Y447306D03*
X322986Y467109D03*
X330115Y490303D03*
X335162Y502791D03*
X326740Y495763D03*
X329672Y502057D03*
X326170Y518386D03*
X335860Y516486D03*
X336010Y531598D03*
X329348Y533403D03*
X324927Y546013D03*
X328592Y541146D03*
X328352Y545412D03*
X325588Y541447D03*
X332408Y544097D03*
X323088Y561503D03*
X323188Y564503D03*
X330388Y565803D03*
X332388Y567703D03*
X328088Y567503D03*
X323931Y589733D03*
X323346Y621930D03*
X329110Y623514D03*
X330440Y639504D03*
X328032Y642674D03*
X337070Y639759D03*
X326350Y638968D03*
X332710Y642694D03*
X328760Y657144D03*
X327540Y653432D03*
X335610Y658177D03*
X332747Y655636D03*
X332190Y659883D03*
X329912Y662383D03*
X335915Y675011D03*
X335390Y667895D03*
X326890Y676159D03*
X327257Y672408D03*
X333180Y665611D03*
X335130Y670744D03*
X334313Y663113D03*
X327500Y667244D03*
X324970Y665128D03*
X337030Y677894D03*
X337798Y686721D03*
X324120Y703114D03*
X336110Y693934D03*
X331520Y701642D03*
X332720Y698170D03*
X330410Y712895D03*
X325560Y713391D03*
X329590Y724283D03*
X334640Y725035D03*
X338270Y733387D03*
X338460Y724585D03*
X326280Y775980D03*
X337800Y774677D03*
X346600Y38561D03*
X346150Y36030D03*
X353060Y61504D03*
X349490Y57698D03*
X352578Y74292D03*
X339750Y73383D03*
X340543Y88647D03*
X345463Y90837D03*
X353713Y93057D03*
X344873Y94847D03*
X343070Y99372D03*
X340450Y101914D03*
X343743Y120967D03*
X351503Y130972D03*
Y127972D03*
X341693Y286010D03*
X340792Y307107D03*
X353903Y314077D03*
X353841Y306194D03*
X339370Y329176D03*
X341910Y325739D03*
X344720D03*
X339600Y332076D03*
X343880Y356989D03*
X349110Y375767D03*
X352420Y375672D03*
X346020Y374075D03*
X343430Y385937D03*
X343770Y382166D03*
X351650Y420270D03*
X346862Y424850D03*
X345270Y452745D03*
X346750Y466532D03*
X352890Y479656D03*
X348000Y479150D03*
X352260Y483029D03*
X338762Y479636D03*
X339506Y482841D03*
X348220Y486484D03*
X352160Y502138D03*
X351250Y499752D03*
X348870Y501571D03*
X343420Y497966D03*
X353400Y507260D03*
X353460Y504536D03*
X348190Y511550D03*
X353120Y510003D03*
X350690Y516376D03*
X340902Y503742D03*
X352940Y518025D03*
X341512Y512429D03*
X350902Y512520D03*
X346350Y517286D03*
X340182Y531787D03*
X351110Y531835D03*
X340330Y541931D03*
X341011Y537828D03*
X342190Y565848D03*
X351964Y599332D03*
X340340Y638054D03*
X340669Y644827D03*
X348480Y638558D03*
X345580Y638109D03*
X347670Y642285D03*
X351722Y659319D03*
X340630Y655093D03*
X351730Y649206D03*
X353902Y667128D03*
X351730Y663450D03*
X340530Y675658D03*
X351720Y670018D03*
X338970Y670776D03*
X340870Y665042D03*
X353260Y688757D03*
X351810Y706800D03*
X339750Y695271D03*
X339010Y700406D03*
X338926Y697752D03*
X352400Y722132D03*
X339300Y716800D03*
X342230Y720936D03*
X341190Y712379D03*
X352010Y713968D03*
X342230Y709384D03*
X345610Y733982D03*
X354060Y734790D03*
X350720Y745722D03*
X344710Y785782D03*
X350450Y784982D03*
X363025Y12926D03*
X366159Y21822D03*
X361930Y60031D03*
X367300Y60442D03*
X365670Y64458D03*
X362133Y90877D03*
X367776Y91746D03*
X358343Y90948D03*
X369670Y99845D03*
X361470Y101757D03*
X354943Y104191D03*
X354448Y108092D03*
X367350Y123927D03*
X365283Y128125D03*
X364220Y296795D03*
X365970Y299194D03*
X356835Y313894D03*
X369280Y300916D03*
X367220Y303202D03*
X369040Y316735D03*
X369934Y322946D03*
X365026Y332478D03*
X362540Y361443D03*
X354690Y377000D03*
X364645Y377065D03*
X364880Y384455D03*
X364580Y391273D03*
X366140Y407639D03*
X360350Y395873D03*
X355250Y420679D03*
X365850Y414874D03*
X368660Y449478D03*
X369500Y445873D03*
X354565Y451562D03*
X354750Y445325D03*
X369507Y464391D03*
X358182Y531231D03*
X357820Y534561D03*
X368825Y539776D03*
X369918Y592253D03*
X369848Y588903D03*
X360647Y602636D03*
X354973Y605588D03*
Y602588D03*
Y611588D03*
X361473Y620588D03*
X354973Y614588D03*
Y620588D03*
Y623588D03*
X361562Y645175D03*
X363530Y629727D03*
X365990Y645272D03*
X367870Y650239D03*
X364980Y655266D03*
X363340Y650512D03*
X361650Y658537D03*
X361580Y652755D03*
X368200Y672132D03*
X368100Y668133D03*
X361810Y675011D03*
X365620Y663069D03*
X361660Y671306D03*
X365380Y668972D03*
X365160Y672922D03*
X361760Y668716D03*
X367066Y681094D03*
X364320Y680434D03*
X367496Y690248D03*
X361510Y680886D03*
X362040Y684875D03*
X364649Y684022D03*
X364765Y687963D03*
X365090Y676923D03*
X367480Y705169D03*
X367614Y693053D03*
X361580Y703860D03*
X363590Y702324D03*
X364115Y692990D03*
X367520Y701710D03*
X367350Y713661D03*
X357830Y718682D03*
X354520Y728701D03*
X363460Y735388D03*
X364750Y727821D03*
X364090Y748565D03*
X354420Y749198D03*
X357610Y748302D03*
X366860Y739956D03*
X354870Y771388D03*
X360160Y775523D03*
X363300Y781303D03*
X367904Y778327D03*
X371180Y17789D03*
X370960Y20577D03*
X381907Y21507D03*
X383280Y59940D03*
X376006Y60991D03*
X383247Y64141D03*
X373560Y63973D03*
X372776Y91746D03*
X382087Y103647D03*
X380483Y99047D03*
X378733Y105987D03*
X384863Y95437D03*
X376100Y108780D03*
X376723Y94178D03*
X378183Y124904D03*
X374040Y304980D03*
X373640Y301078D03*
X370460Y305908D03*
X371090Y303487D03*
X384248Y319157D03*
X372080Y330574D03*
X379560Y374955D03*
X379720Y372257D03*
X378830Y386352D03*
X382620Y391882D03*
X379300Y380862D03*
X379286Y378015D03*
X379750Y383965D03*
X382190Y388077D03*
X376600Y408045D03*
X382680Y408202D03*
X371260Y412879D03*
X383750Y437058D03*
X372320Y439514D03*
X371950Y430527D03*
X378910Y430874D03*
X371080Y448276D03*
X372710Y445705D03*
X375190Y463996D03*
X381239Y467171D03*
X371080Y481589D03*
X374207Y479329D03*
X381760Y496004D03*
X374203Y491029D03*
X376540Y498385D03*
X383617Y517862D03*
X373538Y520213D03*
X376528Y520138D03*
X379733Y549392D03*
X370309Y550322D03*
X377150Y543151D03*
X376490Y540574D03*
X382596Y537379D03*
X382333Y540414D03*
X385410Y566122D03*
X373448Y589053D03*
X373518Y592403D03*
X383034Y640267D03*
X373218Y634217D03*
X382580Y637413D03*
X379093Y657739D03*
X376650Y654157D03*
X379492Y650239D03*
X376089Y646156D03*
X373680Y662417D03*
X376087Y670156D03*
X377211Y673197D03*
X379461Y675246D03*
X379462Y666156D03*
X379791Y679454D03*
X376946Y689985D03*
X377681Y694244D03*
X377679Y701168D03*
X377669Y706237D03*
X377100Y697218D03*
X371170Y711574D03*
X382960Y711431D03*
X372110Y720308D03*
X376190Y711259D03*
X375548Y731459D03*
X375834Y727459D03*
X377840Y724388D03*
X376770Y734898D03*
X373500Y748457D03*
X392600Y20548D03*
X389240D03*
X397655Y21336D03*
X392250Y59899D03*
X389690Y60665D03*
X401310Y61439D03*
X397790Y61360D03*
Y69610D03*
X390355Y75775D03*
X401220Y65155D03*
X392493Y92647D03*
X400163Y99177D03*
X391310Y99570D03*
X399613Y104657D03*
X391233Y96093D03*
X398088Y128455D03*
X393088D03*
X399598Y260251D03*
X398258Y252341D03*
X394378Y260501D03*
X399608Y275211D03*
X393458Y282931D03*
X392508Y275581D03*
X398038Y292571D03*
X399880Y319568D03*
X390080Y331575D03*
X389740Y404725D03*
X395740Y407528D03*
X393370Y411618D03*
X392076Y470970D03*
X387080Y486400D03*
X385940Y482478D03*
X388890Y480439D03*
X386410Y477576D03*
X389670Y477262D03*
X388982Y496939D03*
X395690Y512774D03*
X396350Y532016D03*
X396558Y522251D03*
X396470Y527847D03*
X396048Y540127D03*
X395922Y536127D03*
X396590Y549310D03*
X399590Y553502D03*
X390000Y567345D03*
X396520Y567444D03*
X393596Y567630D03*
X401091Y587054D03*
X398386Y587126D03*
X401422Y597270D03*
Y599770D03*
X398822Y600399D03*
X391447Y611973D03*
X394389Y604053D03*
X401353Y624007D03*
X399223Y644930D03*
X395701Y637430D03*
X399440Y637340D03*
X394380Y643389D03*
X396366Y653229D03*
X399363Y653588D03*
X389856Y645705D03*
X386173Y665065D03*
X391938Y672320D03*
X392097Y676231D03*
X399873Y666411D03*
X396550Y680266D03*
X399829Y690191D03*
X400968Y686699D03*
X400408Y681193D03*
X390660Y686923D03*
X391910Y696742D03*
X392080Y692796D03*
X391740Y705957D03*
X398620Y701411D03*
X390950Y701922D03*
X396150Y708926D03*
X400730Y721954D03*
X394840Y711437D03*
X404310Y65213D03*
X410713Y76187D03*
X404813Y93887D03*
X407303Y95117D03*
X408072Y109146D03*
X404738Y260421D03*
X402948Y253251D03*
X405970Y256489D03*
X401618Y267351D03*
X403148Y270191D03*
X405248Y272731D03*
X403628Y292201D03*
X408790Y317049D03*
X411240Y316482D03*
X414870Y455166D03*
Y450976D03*
X406352Y471405D03*
X410607Y485620D03*
X413607D03*
X409985Y508431D03*
X413138Y504813D03*
X413222Y508054D03*
X411439Y516956D03*
X407865Y516627D03*
X405348Y506316D03*
X402458Y505903D03*
X401556Y508937D03*
X409251Y521763D03*
X412088Y521721D03*
X407776Y527426D03*
X405954Y532502D03*
X404336Y545280D03*
X408486Y537333D03*
X416515Y547602D03*
X404578Y551838D03*
X408736Y551529D03*
X413342Y556219D03*
X406884Y594176D03*
X406881Y591322D03*
X412783Y605500D03*
X416454Y621319D03*
X413105Y613739D03*
X403904Y618333D03*
X410085Y618329D03*
X409520Y637387D03*
X414760Y636225D03*
X403970Y642364D03*
X406100Y631851D03*
X413535Y646804D03*
X411982Y660285D03*
X413718Y655267D03*
X410918Y649363D03*
X413966Y675624D03*
X415218Y664203D03*
X411675Y672654D03*
X411065Y667516D03*
X414183Y686151D03*
X411862Y688027D03*
X413643Y680004D03*
X412250Y683196D03*
X411149Y678387D03*
X412878Y693183D03*
X414550Y707464D03*
X414318Y700979D03*
X414810Y696968D03*
X402540Y710649D03*
X412080Y719034D03*
X414080Y721334D03*
X415730Y710897D03*
X406720Y723395D03*
X409010Y726147D03*
X415780Y747078D03*
X421893Y123537D03*
X421640Y228403D03*
Y223403D03*
X428405Y245194D03*
X424961Y241203D03*
X418905Y245694D03*
X426992Y250016D03*
X422528Y253531D03*
X426335Y267062D03*
X418575Y263691D03*
X420858Y261331D03*
X427817Y258829D03*
X421728Y279141D03*
X428748Y275222D03*
X418588Y286681D03*
X421128Y292601D03*
X423178Y284601D03*
X427909Y286759D03*
X427468Y292287D03*
X421710Y424527D03*
X430340Y416573D03*
X432450Y418766D03*
X422120Y418288D03*
X432960Y414886D03*
X422080Y414644D03*
Y410454D03*
X421770Y433187D03*
X422860Y441790D03*
X422760Y445581D03*
X425870Y449509D03*
X422460Y449467D03*
X429670Y449552D03*
X419420Y453168D03*
X428747Y463314D03*
X419420Y457358D03*
X428747Y468770D03*
X431280Y514223D03*
X431356Y516836D03*
X422050Y517028D03*
X425999Y516211D03*
X424873Y513921D03*
X426068Y546048D03*
X417979Y545352D03*
X428039Y548119D03*
X421461Y547703D03*
X420883Y556729D03*
X428039Y556539D03*
X423861Y556535D03*
X431145Y556608D03*
X424904Y586283D03*
X429340Y596874D03*
X425151Y608429D03*
X431520Y607039D03*
X420245Y636004D03*
X417422Y637592D03*
X432180Y647458D03*
X425334Y656419D03*
X422007Y652732D03*
X423623Y645396D03*
X422026Y656883D03*
X429820Y656709D03*
X421080Y665945D03*
X422222Y675226D03*
X426100Y667884D03*
X427900Y679709D03*
X430861Y679156D03*
X422981Y690351D03*
X430862Y691156D03*
X430813Y687156D03*
X427210Y691934D03*
X423055Y696713D03*
X430618Y699156D03*
X430667Y703156D03*
X430731Y707156D03*
X430813Y695156D03*
X427230Y707377D03*
X426391Y701173D03*
X423242Y707949D03*
X425590Y695895D03*
X421350Y694003D03*
X430738Y711156D03*
X427130Y717871D03*
X421730Y717398D03*
X429240Y721014D03*
X424410Y718429D03*
X417330Y717420D03*
X431440Y723955D03*
X420290Y733741D03*
X423900Y736055D03*
X424200Y733399D03*
X426440Y724240D03*
X421690Y779548D03*
X417880Y786361D03*
X428250Y772054D03*
X426900Y779752D03*
X442380Y75513D03*
X439670Y70044D03*
X446920Y78358D03*
X447715Y97926D03*
X446522Y146932D03*
X444550Y184057D03*
X442520Y223623D03*
X441580Y250730D03*
X443212Y240957D03*
X441498Y266731D03*
X441792Y259473D03*
X445540Y288853D03*
X445890Y283317D03*
X438340Y403375D03*
X439150Y400930D03*
X443240Y401984D03*
X446830Y400551D03*
X445900Y403460D03*
X436370Y410543D03*
X444020Y410374D03*
X439830D03*
X446660Y413325D03*
X446950Y417162D03*
X440900Y446260D03*
X436710D03*
X444850Y446337D03*
X438390Y456129D03*
X438520Y452324D03*
X433720Y449467D03*
X444920Y485259D03*
X447770Y485290D03*
X437716Y476295D03*
X445366Y490657D03*
X445199Y494590D03*
X439749Y506523D03*
X439762Y515540D03*
Y523757D03*
X447781Y523888D03*
X434605Y521488D03*
X442763Y549595D03*
X445838Y538085D03*
X435998Y539726D03*
X434203Y542897D03*
X438722Y538842D03*
X441063Y540563D03*
X448329Y534995D03*
X441326Y556050D03*
X437832Y556374D03*
X434187Y556444D03*
X442240Y553337D03*
X441230Y587341D03*
X447830Y588739D03*
X446378Y582681D03*
X435319Y600123D03*
X440040Y608537D03*
X437120Y612933D03*
X448460Y625960D03*
X445604Y629045D03*
X437100Y643793D03*
X446500Y645075D03*
X443850Y634754D03*
X439250Y630973D03*
X434681Y642639D03*
X435420Y647117D03*
X437509Y648996D03*
X435972Y655595D03*
X444700Y651900D03*
X445270Y660832D03*
X447210Y665143D03*
X436000Y675706D03*
X435539Y671628D03*
X436445Y667628D03*
X447161Y673564D03*
X444458Y669350D03*
X440688Y684438D03*
Y689438D03*
X440690Y702386D03*
X440688Y694438D03*
X442650Y719485D03*
X446260Y722014D03*
X444530Y723917D03*
X440660Y712065D03*
X439200Y722093D03*
X442120Y724781D03*
X447680Y733564D03*
X444370Y770152D03*
X434540Y778500D03*
X441006Y785297D03*
X458120Y44721D03*
X464170Y56436D03*
X458598Y77967D03*
X461516Y78275D03*
X461594Y99342D03*
X449538Y105144D03*
X453168D03*
X453940Y98586D03*
X460412Y105704D03*
X457912D03*
X462912D03*
X461880Y150596D03*
X454763Y183503D03*
X453340Y185670D03*
X457482Y183523D03*
X462790Y183489D03*
X459000Y200500D03*
X450650Y203785D03*
X453620Y245162D03*
X459990Y245930D03*
X456800Y259233D03*
X459108Y253181D03*
X449860Y267121D03*
X456530Y256034D03*
X449860Y272121D03*
X452900Y281647D03*
X453810Y289325D03*
X451790Y300129D03*
X448970Y403846D03*
X451950Y402434D03*
X463540Y495717D03*
X457537Y495546D03*
X454770Y495587D03*
X450813Y492993D03*
X463565Y515723D03*
X452895Y510061D03*
X449402Y515514D03*
X451504Y529734D03*
X450540Y521331D03*
X463991Y531504D03*
X451325Y525981D03*
X456722Y529536D03*
X454022Y541052D03*
X463031Y543563D03*
X453917Y550069D03*
X450367Y540720D03*
X453700Y545047D03*
X453854Y555069D03*
X455890Y592792D03*
X450778Y583106D03*
X462270Y612911D03*
X459690Y626423D03*
X464050Y633877D03*
X458903Y644884D03*
X461997Y654507D03*
X463178Y647483D03*
X460587Y669424D03*
X457138Y663251D03*
X463020Y661023D03*
X464330Y663251D03*
X458820Y674137D03*
X459950Y722720D03*
X453960Y723142D03*
X449060Y721761D03*
X457060Y722427D03*
X460822Y712620D03*
X451820Y712210D03*
X454070Y714226D03*
X455410Y734113D03*
X450410Y733682D03*
X451320Y725044D03*
X461565Y785806D03*
X463750Y780452D03*
X454120Y785923D03*
X475310Y59746D03*
X475030Y63879D03*
X479450Y63721D03*
X471500Y138000D03*
X473200Y140300D03*
X468400Y135800D03*
X470324Y133424D03*
X474813Y162220D03*
X467473Y159766D03*
X473951Y157235D03*
X473950Y172124D03*
X475760Y168747D03*
X472670Y166398D03*
X473580Y177859D03*
X474630Y174843D03*
X480220Y185766D03*
X475770Y186451D03*
X468452Y197934D03*
X471300Y201900D03*
X476400Y203100D03*
X478000Y212500D03*
X466200Y207300D03*
X471795Y267941D03*
X464810Y311253D03*
X470090Y332824D03*
X475190Y339013D03*
X465913Y402659D03*
X465883Y399834D03*
X480118Y479107D03*
Y474107D03*
X466307Y495676D03*
X467677Y510055D03*
X467496Y513179D03*
X466587Y515764D03*
X467586Y506807D03*
X471804Y561085D03*
Y556085D03*
X471190Y593964D03*
X468740Y585897D03*
X469890Y596580D03*
X473294Y613207D03*
X476320Y629280D03*
X465580Y641417D03*
X469229Y638135D03*
X475820Y635422D03*
X474946Y659376D03*
X468810Y652180D03*
X479512Y649436D03*
X468540Y655799D03*
X466980Y667059D03*
X469977Y676496D03*
X468260Y664366D03*
X469467Y679915D03*
X479409Y682305D03*
X479354Y677054D03*
X477710Y722299D03*
X466620Y714137D03*
X473940Y714184D03*
X470550Y724034D03*
X473560Y724951D03*
X465850Y733428D03*
X476980Y736594D03*
X476160Y734205D03*
X471780Y786300D03*
X486810Y60785D03*
X483240Y60546D03*
X487030Y68075D03*
X488438Y109623D03*
X492955Y99440D03*
X494355Y108674D03*
X491875Y125222D03*
X487140Y123397D03*
X484350Y112811D03*
X487020Y119754D03*
X494910Y133316D03*
X487857Y152147D03*
X488570Y147486D03*
X492424Y142234D03*
X494467Y148867D03*
X487740Y161235D03*
X488220Y157515D03*
X490130Y163086D03*
X493670Y171871D03*
X489040Y169483D03*
X482500Y184169D03*
X487080Y180918D03*
X482980Y181071D03*
X488850Y175419D03*
X494210Y175035D03*
X487839Y194142D03*
X487464Y198566D03*
X488017Y203716D03*
X486370Y189279D03*
X487168Y214568D03*
X491320Y231809D03*
X492700Y223800D03*
X484169Y272867D03*
X484780Y314090D03*
X494850Y315733D03*
X480830Y333921D03*
X486300Y422150D03*
X481300D03*
X495500Y447465D03*
X482880Y467935D03*
Y462935D03*
X492260Y482826D03*
X494980Y482979D03*
X490334Y497342D03*
X485510Y536673D03*
X483209Y545250D03*
Y550250D03*
X490661Y547148D03*
X489962Y540849D03*
X483838Y566194D03*
Y556148D03*
Y561148D03*
Y571194D03*
X485738Y587125D03*
X490738D03*
X481340Y593296D03*
X494238Y600441D03*
X490600Y608136D03*
X489800Y600200D03*
X487832Y624429D03*
X490040Y622140D03*
X491380Y639279D03*
X495900Y641804D03*
X480310Y642224D03*
X492310Y650516D03*
X482180Y646278D03*
X481253Y654837D03*
X493020Y646701D03*
X484700Y660355D03*
X482398Y673087D03*
X482544Y668042D03*
X491044Y667604D03*
X491060Y671604D03*
X490120Y662703D03*
X492770Y665090D03*
X492294Y682347D03*
X483056Y679628D03*
X481227Y685366D03*
X491167Y687507D03*
X481227Y691366D03*
X494340Y691623D03*
X491067Y699656D03*
X491380Y694656D03*
X490900Y706145D03*
X481227Y696366D03*
X495560Y694781D03*
X488180Y719244D03*
X490890Y714898D03*
X488090Y710545D03*
X480620Y734244D03*
X480770Y778125D03*
X485870Y776087D03*
X491720Y776713D03*
X495110Y771733D03*
X502900Y57670D03*
X496955Y99958D03*
X508955Y99978D03*
X500955Y100139D03*
X504955Y99830D03*
X500310Y109211D03*
X497430Y124024D03*
X504750Y111749D03*
X509691Y112938D03*
X499456Y128666D03*
X509710Y127269D03*
X500215Y136449D03*
X502183Y156709D03*
X500963Y162261D03*
X496360Y167221D03*
X501040Y177297D03*
X498940Y179744D03*
X510000Y173500D03*
X502999Y180541D03*
X499154Y194198D03*
X509100Y191900D03*
X505580Y192555D03*
X499225Y205296D03*
X506234Y207368D03*
X504941Y227859D03*
X498867Y227773D03*
X499405Y242877D03*
X507000Y239000D03*
X504160Y255584D03*
X511070Y310719D03*
X509140Y338005D03*
X497111Y388567D03*
X502111D03*
X509486Y433829D03*
X497818Y440265D03*
X506456Y446928D03*
X502938Y463823D03*
X505843Y465018D03*
X498119Y470011D03*
X511230Y499059D03*
X506230D03*
X498920Y523803D03*
X503958Y529405D03*
X504613Y525200D03*
X501331Y528932D03*
X503338Y549825D03*
Y544825D03*
X500138Y563025D03*
Y558625D03*
X500338Y566425D03*
X500438Y574925D03*
X500419Y578644D03*
X500538Y572025D03*
X500338Y569425D03*
X500538Y588525D03*
X505738Y590525D03*
X500098Y608885D03*
X509238Y608515D03*
X508024Y613598D03*
X500538Y600925D03*
X504980Y616425D03*
X508400Y617803D03*
X502080Y622999D03*
X498350Y627580D03*
X505780Y642543D03*
X501120Y633249D03*
X510700Y634300D03*
X496690Y633589D03*
X501940Y644073D03*
X504836Y657097D03*
X503680Y659666D03*
X505690Y654419D03*
X508061Y645381D03*
X504295Y649612D03*
X498040Y675306D03*
X498870Y668324D03*
X504114Y670830D03*
X496453Y670876D03*
X501914Y675624D03*
X504241Y665809D03*
X497320Y665216D03*
X506376Y687436D03*
X506470Y683512D03*
X496577Y684553D03*
X505580Y679105D03*
X496277Y678185D03*
X501540Y681970D03*
X506409Y691373D03*
X500710Y706582D03*
X497350Y699767D03*
X506092Y697575D03*
X510608Y717448D03*
X499842Y710582D03*
X499452Y714582D03*
X498080Y733252D03*
X509855Y724107D03*
X500260Y729094D03*
X501604Y733003D03*
X501890Y746663D03*
X507935Y785704D03*
X511770Y779940D03*
X499270Y776431D03*
X504440Y772548D03*
X513120Y72069D03*
X512955Y100428D03*
X524955Y99359D03*
X516955Y100333D03*
X520955Y100444D03*
X512878Y108635D03*
X519625Y108543D03*
X526835Y108314D03*
X525570Y124623D03*
X516146Y113121D03*
X522111Y113310D03*
X518640Y125539D03*
X518725Y170525D03*
X512600Y178900D03*
X515600Y172800D03*
X521320Y178184D03*
X516100Y178100D03*
X526621Y177079D03*
X512200Y204200D03*
X526443Y194116D03*
X514500Y194300D03*
X525293Y191705D03*
X515231Y191334D03*
X520015Y194584D03*
X523593Y198171D03*
X512200Y196000D03*
X520068Y207142D03*
X516551Y214987D03*
X512160Y217073D03*
X526657Y207363D03*
X524405Y212531D03*
X514766Y208222D03*
X515675Y234555D03*
X524675Y234766D03*
X517189Y226229D03*
X517670Y247527D03*
X515675Y254098D03*
X525480Y268959D03*
X518590Y310129D03*
X526250Y310940D03*
X519650Y320384D03*
X522420Y315475D03*
X517260Y315978D03*
X523930Y321642D03*
X514400Y340829D03*
X520510Y337299D03*
X527438Y340353D03*
X526440Y422428D03*
X527300Y417368D03*
X517929Y439676D03*
X523667Y438452D03*
X522379Y431974D03*
X512867Y443679D03*
X516353Y443517D03*
X523838Y442723D03*
X525603Y480187D03*
X525638Y484023D03*
X519938Y493125D03*
X524938D03*
X514430Y511801D03*
X519430D03*
X518938Y540425D03*
X521938Y540325D03*
X516380Y540364D03*
X525338Y540125D03*
X516738Y562425D03*
X513738D03*
X515413Y590950D03*
X524638Y590225D03*
X520228Y590335D03*
X525570Y602466D03*
X514058Y605055D03*
X523800Y611145D03*
X520370Y625158D03*
X526300Y623621D03*
X518920Y615387D03*
X511910Y638722D03*
X514320Y641085D03*
X515438Y649996D03*
X525692Y654862D03*
X517328Y655529D03*
X521516Y650576D03*
X517806Y670102D03*
X517222Y673917D03*
X518800Y665776D03*
X526610Y672286D03*
X515541Y661845D03*
X526430Y664730D03*
X518382Y678247D03*
X515429Y692278D03*
X526600Y679117D03*
X517888Y687901D03*
X518947Y685122D03*
X527111Y686052D03*
X515429Y697278D03*
X512548Y722093D03*
X514620Y713193D03*
X517443Y717011D03*
X517775Y711203D03*
X522865Y711178D03*
X514498Y716473D03*
X516940Y735683D03*
X521800Y732667D03*
X514420Y733131D03*
X524576Y733227D03*
X512610Y747115D03*
X525110Y774395D03*
X519440Y772861D03*
X542180Y93534D03*
X539510Y108742D03*
X536955Y100257D03*
X532955Y108669D03*
X528955Y99781D03*
X532955Y100604D03*
X535960Y112850D03*
X527613Y113373D03*
X542700Y112881D03*
X538655Y151415D03*
X538294Y159415D03*
X529272Y178311D03*
X542002Y180100D03*
X539500Y196500D03*
X536232Y192086D03*
X529592Y192999D03*
X533474Y196500D03*
X541657Y207645D03*
X532320Y209470D03*
X538525Y213425D03*
X532500Y206500D03*
X534208Y227832D03*
X528105Y230594D03*
X536972Y242993D03*
X536476Y238993D03*
X535772Y250076D03*
X539267Y267102D03*
X532794Y282068D03*
X530119Y280101D03*
X528680Y317349D03*
X541380Y340358D03*
X543110Y333848D03*
X536180Y341432D03*
X536170Y336603D03*
X531795Y340409D03*
X531430Y337074D03*
X527603Y337208D03*
X540700Y418852D03*
X541650Y422280D03*
X536440Y421973D03*
X530940Y422207D03*
X529968Y440216D03*
X529028Y430469D03*
X535352Y440414D03*
X540141Y442994D03*
X534738Y445523D03*
X541838Y450723D03*
X538038Y488323D03*
X533038D03*
X543280Y491040D03*
X530438Y529525D03*
X541538Y529625D03*
X534401Y529562D03*
X528138Y539925D03*
X540701Y590162D03*
X527638Y590325D03*
X535776Y590487D03*
X530338Y590325D03*
X529408Y603485D03*
X540540Y601008D03*
X538828Y602945D03*
X542848Y602975D03*
X535048Y602885D03*
X541980Y620227D03*
X527828Y615387D03*
X532420Y615484D03*
X539471Y632476D03*
X530779Y637354D03*
X532479Y633588D03*
X541440Y647594D03*
X531970Y650491D03*
X542424Y654821D03*
X536557Y655498D03*
X539120Y670129D03*
X529525Y669349D03*
X529899Y661020D03*
X539734Y675020D03*
X539830Y667332D03*
X531599Y689838D03*
X533270Y679351D03*
X531597Y697509D03*
X535272Y711217D03*
X535062Y708679D03*
X530012Y708618D03*
X543193Y710787D03*
X539577Y721891D03*
X537503Y710088D03*
X528388Y722903D03*
X540062Y708779D03*
X532940Y734810D03*
X531029Y733142D03*
X539650Y780942D03*
X529300Y771341D03*
X533600Y778780D03*
X555938Y97292D03*
X551454Y97154D03*
X547480Y96632D03*
X557995Y110244D03*
X546306Y110193D03*
X550490Y112989D03*
X552173Y138528D03*
X550599Y132596D03*
X550550Y151682D03*
X558059Y154254D03*
X558348Y142511D03*
X551464Y143862D03*
X550604Y168072D03*
X550370Y157461D03*
X557668Y176534D03*
X555510Y173872D03*
X551395Y174172D03*
X555836Y179259D03*
X546000Y180000D03*
X544500Y197500D03*
X546000Y192000D03*
X549909Y207060D03*
X557909Y207537D03*
X555750Y212029D03*
X544500Y207000D03*
X545424Y226722D03*
X546690Y233066D03*
X544990Y231086D03*
X549488Y233003D03*
X549358Y230153D03*
X552120Y232388D03*
X552050Y229124D03*
X550040Y243929D03*
X545703Y245725D03*
X545981Y236287D03*
X550090Y247079D03*
X545116Y266847D03*
X547929Y258102D03*
X557207Y274828D03*
X551341Y274262D03*
X545223Y276895D03*
X557207Y280328D03*
X555072Y289563D03*
X557222Y285109D03*
X553690Y340829D03*
X547340Y339103D03*
X552090Y388953D03*
X548470Y378127D03*
X549760Y407251D03*
X553230D03*
X553750Y410420D03*
X544500Y422583D03*
X557017Y438968D03*
X549574Y432582D03*
X555140Y445940D03*
X546384Y445107D03*
X547488Y452373D03*
X554550Y469674D03*
X545513Y469740D03*
X543338Y459323D03*
X547638Y462356D03*
X546038Y457523D03*
X546250Y490302D03*
X544370Y510267D03*
Y515267D03*
X554860Y531701D03*
X549920Y527242D03*
X551161Y547148D03*
X545138Y539725D03*
X551538Y540325D03*
X551338Y544225D03*
Y551100D03*
X551438Y563825D03*
X551238Y571725D03*
X547000Y590163D03*
X551238Y584025D03*
X543850Y590313D03*
X550149Y604639D03*
X543400Y625963D03*
X552350Y614028D03*
X558281Y637840D03*
X551030Y637200D03*
X543400Y635615D03*
X549314Y647594D03*
X551230Y652844D03*
X555356Y665156D03*
Y669156D03*
X555308Y673156D03*
X551283Y670800D03*
X555357Y689156D03*
X555284Y685156D03*
X555235Y681156D03*
X555308Y677156D03*
X551283Y699243D03*
X555150Y697156D03*
X555271Y693156D03*
X547542Y711523D03*
X544934Y720820D03*
X550535Y721903D03*
X555551Y722342D03*
X557488Y713709D03*
X553725Y717251D03*
X550004Y709559D03*
X555062Y708679D03*
X545062D03*
X553193Y724847D03*
X546566Y724119D03*
X544082Y724460D03*
X549049Y724412D03*
X557426Y724436D03*
X557978Y734053D03*
X545300Y783152D03*
X550940Y771858D03*
X554870Y779438D03*
X566090Y109136D03*
X560938Y97195D03*
X569559Y103123D03*
X565938Y96820D03*
X563230Y150222D03*
X564076Y145372D03*
X563410Y165289D03*
X563274Y162169D03*
X562195Y159015D03*
X563129Y178369D03*
X559646Y174476D03*
X569682Y195199D03*
X572782D03*
X569874Y231795D03*
X572690Y226569D03*
X572020Y222393D03*
X567980Y222353D03*
X568410Y226647D03*
X561258Y230153D03*
X566248Y230283D03*
X563506Y232027D03*
X564274Y279395D03*
X566774Y275195D03*
X566876Y289890D03*
X561525Y298192D03*
X560865Y285434D03*
X565953Y301635D03*
X565310Y412700D03*
X565977Y456156D03*
X566059Y460956D03*
X572440Y464323D03*
Y469323D03*
X562340Y484252D03*
X573840Y512108D03*
X564370Y504117D03*
Y509117D03*
X567493Y532225D03*
X562308Y536895D03*
X566298Y548465D03*
X563188Y541925D03*
X566338Y554235D03*
X561174Y564471D03*
X565858Y576195D03*
X561198Y581793D03*
X566378Y567725D03*
X561608Y571775D03*
X565398Y584765D03*
X568163Y595115D03*
X561568Y589355D03*
X574071Y606204D03*
X568930Y607754D03*
X566053Y627509D03*
X571650Y625998D03*
X574730Y625521D03*
X565647Y637705D03*
X565556Y632431D03*
X571790Y646799D03*
X559440Y650767D03*
X566950Y659439D03*
X563850Y659575D03*
X563840Y653515D03*
X565168Y664614D03*
Y674614D03*
Y669614D03*
X563586Y682137D03*
X563577Y692284D03*
X563441Y676872D03*
X565168Y679614D03*
X563393Y686908D03*
X565168Y689614D03*
Y694614D03*
Y699614D03*
X560544Y718091D03*
X569604Y721248D03*
X574190Y717805D03*
X564319Y721587D03*
X562540Y713454D03*
X560062Y708679D03*
X570614Y713237D03*
X565062Y708679D03*
X571232Y732545D03*
X566798Y734023D03*
X569680Y771106D03*
X560150Y781347D03*
X562700Y772391D03*
X572720Y777184D03*
X588943Y98963D03*
X589308Y103990D03*
X580501Y138336D03*
X583829Y132232D03*
X583547Y128232D03*
X587968Y138765D03*
X581565Y154969D03*
X583970Y144589D03*
X580180Y148894D03*
X579540Y143304D03*
X579897Y161355D03*
X582792Y167632D03*
X581915Y179955D03*
X585580Y210516D03*
X583707Y220762D03*
X587707Y220728D03*
X579707Y229395D03*
X585579Y230095D03*
X576105Y231626D03*
X581474Y274795D03*
X575880Y293016D03*
X575908Y295606D03*
X588607Y305034D03*
X576650Y311446D03*
X581650D03*
X585984Y323246D03*
X579788Y354743D03*
X589070Y423525D03*
X578830Y448192D03*
X588153Y459599D03*
X578840Y512108D03*
X583890Y537093D03*
X576208Y542405D03*
X575838Y548935D03*
X588540Y557418D03*
X584413Y563198D03*
X583538Y552225D03*
X575038Y554725D03*
X575138Y559825D03*
X577778Y556355D03*
X578110Y582149D03*
X582023Y571242D03*
X578399Y585696D03*
X588780Y611056D03*
X586810Y603344D03*
X577000Y620029D03*
X585500Y620926D03*
X588780Y616056D03*
X588950Y650070D03*
X583930Y652439D03*
X579020Y658250D03*
X577217Y652002D03*
X576987Y660180D03*
X580740Y653286D03*
X580637Y663629D03*
X576846Y675985D03*
X579076Y669603D03*
X576520Y667750D03*
X589050Y680160D03*
X579980Y683140D03*
X576644Y679562D03*
X578030Y690236D03*
X577010Y682718D03*
X576519Y687665D03*
X589500Y690546D03*
X579151Y707857D03*
X588151D03*
X584101Y707893D03*
X576442Y705492D03*
X585400Y697289D03*
X584312Y710716D03*
X579220Y720776D03*
X585693Y722428D03*
X583440Y724927D03*
X577570Y734118D03*
X580510Y724421D03*
X587170Y773768D03*
X579240Y775147D03*
X603158Y91535D03*
X601374Y94048D03*
X604543Y94886D03*
X598123Y102023D03*
X595318Y98854D03*
X593850Y103755D03*
X592392Y100623D03*
X595345Y120216D03*
X605070Y123991D03*
X600118Y112568D03*
X592938Y117657D03*
X595438Y138130D03*
X592938Y140689D03*
Y133232D03*
X594938Y127893D03*
X593537Y161023D03*
X592917Y171906D03*
X593277Y179955D03*
X591707Y221095D03*
Y230162D03*
X595374Y236795D03*
X592858Y247079D03*
X593459Y240780D03*
X594067Y265168D03*
X594174Y256695D03*
X593874Y262395D03*
X590874Y275195D03*
X594374Y271395D03*
X596574Y276393D03*
X593607Y305034D03*
X590984Y323246D03*
X598551Y329541D03*
X601450Y326509D03*
X604338Y338285D03*
X600770Y358702D03*
X597440Y391690D03*
X594860Y395088D03*
X600680Y412780D03*
X590720Y456076D03*
X591100Y450128D03*
X605800Y463167D03*
X603819Y485332D03*
X598670Y508170D03*
X603010Y527908D03*
X596560Y536108D03*
X606300Y551844D03*
X604820Y555040D03*
X604437Y557956D03*
X596050Y557563D03*
X592437Y566543D03*
X601043Y567781D03*
X605396Y590552D03*
X605286Y584152D03*
X605290Y594166D03*
X596401Y589852D03*
X593867Y595695D03*
X602314Y607641D03*
Y602641D03*
X593867Y600695D03*
X605010Y641435D03*
X600980Y641533D03*
X591279Y656223D03*
X596998Y658008D03*
X591840Y659568D03*
X596470Y655231D03*
X602332Y671156D03*
X600736Y668425D03*
X593142Y663828D03*
X600719Y675156D03*
X597300Y663128D03*
X600690Y691896D03*
X600727Y681876D03*
X602020Y679156D03*
X600727Y686876D03*
X604220Y703774D03*
X600650Y707835D03*
X592960Y703291D03*
X601856Y711479D03*
X606146Y713145D03*
X601813Y715579D03*
X598880Y719232D03*
X595950Y708997D03*
X594170Y719290D03*
X603938Y753623D03*
X606270Y774615D03*
X597530Y780191D03*
X592480Y771514D03*
X610543Y107678D03*
X617925Y114064D03*
X613432Y153528D03*
X610415Y237441D03*
X617778Y238873D03*
X612974Y269095D03*
X609150Y328514D03*
X616490Y327534D03*
X607671Y344818D03*
X619190Y336986D03*
X608306Y359971D03*
X611848Y359784D03*
X607855Y352341D03*
X618581Y354818D03*
X617592Y362539D03*
X620238Y364369D03*
X609078Y388557D03*
X619014Y408353D03*
X609078Y393557D03*
X612641Y397478D03*
Y402478D03*
X611050Y423087D03*
X621399Y420400D03*
X611130Y417928D03*
X616258Y422211D03*
X610580Y448662D03*
X609370Y452974D03*
X610010Y456581D03*
X617980Y460408D03*
X613470Y537495D03*
X616320Y537066D03*
X610070Y557588D03*
X621937Y558276D03*
X621840Y555040D03*
X609060Y552101D03*
X610821Y566494D03*
X621937Y567143D03*
X609026Y579132D03*
X617270Y580443D03*
X611520Y596594D03*
X612270Y586543D03*
X612493Y607666D03*
X611254Y617943D03*
X612370Y614143D03*
X615690Y625536D03*
X616730Y633290D03*
X608310Y641603D03*
X611572Y629894D03*
X620510Y639427D03*
X616471Y636215D03*
X613796Y648705D03*
X612950Y656140D03*
X607620Y647169D03*
X615700Y657757D03*
X613200Y661577D03*
X620160Y670594D03*
X615940Y666862D03*
X610693Y679333D03*
X610570Y691156D03*
X610550Y686640D03*
X610810Y683933D03*
X612670Y681438D03*
X612811Y688422D03*
X608975Y708094D03*
X612914Y707630D03*
X610540Y697964D03*
X618020Y700000D03*
X610570Y695156D03*
X607380Y699671D03*
X617930Y703520D03*
X620480Y693827D03*
X609070Y721917D03*
X616070Y720838D03*
X613730Y717663D03*
X620670Y722216D03*
X620830Y717516D03*
X609840Y713617D03*
X619080Y772610D03*
X619030Y778682D03*
X612260Y783106D03*
X609347Y778624D03*
X626380Y85117D03*
X624020Y83243D03*
X623750Y87130D03*
X626380Y88518D03*
X623725Y90422D03*
X626180Y91919D03*
X623820Y93654D03*
X626320Y96084D03*
X623610Y97125D03*
X626180Y99276D03*
X628838Y120216D03*
X628738Y133012D03*
X624800Y184953D03*
Y179953D03*
X634962Y200121D03*
Y195121D03*
X622470Y261628D03*
X635000Y265400D03*
X634212Y281670D03*
X624383Y292591D03*
X631672Y301066D03*
X632376Y305257D03*
X631702Y307880D03*
X632122Y312898D03*
X633773Y310439D03*
X635652Y313118D03*
X636962Y310928D03*
X623820Y321062D03*
X633470Y326710D03*
X628140Y317610D03*
X631860Y321455D03*
X627000Y327926D03*
X622890Y325227D03*
X633652Y315198D03*
X628141Y344818D03*
X630190Y336986D03*
X625190D03*
X624889Y357778D03*
X637738Y392034D03*
X636990Y386464D03*
X627022Y383713D03*
X634511Y389156D03*
X637614Y397259D03*
X630691Y405007D03*
X636938Y402885D03*
X630691Y410007D03*
X636586Y410910D03*
X633455Y427209D03*
X634578Y424964D03*
X635840Y449890D03*
X626250Y450248D03*
X631280Y446007D03*
X635120Y456136D03*
X630570Y451450D03*
X622100Y465822D03*
X625900Y461769D03*
X628250Y471142D03*
X632680Y466669D03*
X636010Y469995D03*
X630420Y491511D03*
X636170Y493028D03*
X622600Y488753D03*
X632157Y511230D03*
X625130Y534199D03*
X634530Y521565D03*
X622798Y546764D03*
X636890Y571351D03*
X624870Y573143D03*
X627084Y578257D03*
X634921Y580163D03*
X627047Y581066D03*
X623940Y628720D03*
X636890Y627095D03*
X629781Y628559D03*
X627986Y625895D03*
X630984Y624829D03*
X622510Y635544D03*
X634137Y631342D03*
X627146Y638932D03*
X623290Y641222D03*
X634137Y639352D03*
X630137Y639312D03*
X631930Y655254D03*
X633970Y723033D03*
X622290Y708516D03*
X628160Y722343D03*
X631690Y733744D03*
X635460Y735130D03*
X636170Y729335D03*
X630040Y745114D03*
X632300Y749755D03*
X636910Y745815D03*
X624010Y746351D03*
X629912Y769200D03*
X625010Y778281D03*
X636390Y775395D03*
X632030Y779137D03*
X632000Y775400D03*
X643957Y53688D03*
X639957Y53849D03*
X639200Y170100D03*
X639350Y250123D03*
X642932Y284768D03*
X640112Y285042D03*
X649995Y296433D03*
X652362Y306598D03*
X640647Y339854D03*
X648450Y338711D03*
X648838Y349785D03*
X642863Y358010D03*
X639838Y349818D03*
X646171Y364676D03*
X648425Y373474D03*
X652139Y377125D03*
X641236Y381616D03*
X645236Y377858D03*
X648493Y417221D03*
X648208Y427819D03*
X643208D03*
X653070Y427500D03*
X650822Y425295D03*
X641690Y443656D03*
X647280Y446851D03*
X653360Y446280D03*
X651080Y455238D03*
X652110Y465238D03*
X651840Y460012D03*
X648920Y457851D03*
X646600Y463571D03*
X648956Y469323D03*
X650521Y482930D03*
X647921Y475778D03*
X651395Y487265D03*
X650790Y497730D03*
X650150Y494337D03*
X638350Y507893D03*
X641842Y516730D03*
X646460Y512967D03*
X652690Y531693D03*
X640470Y523266D03*
X645040Y524444D03*
X645150Y535704D03*
X639673Y576888D03*
X651437Y578943D03*
X646732Y580781D03*
X641870Y580743D03*
X646870Y569443D03*
Y576243D03*
X644636Y627257D03*
X642795Y624818D03*
X648701Y624774D03*
X646940Y643448D03*
X641263Y631393D03*
X649173Y629876D03*
X646737Y639413D03*
X642737D03*
X647870Y649784D03*
X646580Y654775D03*
X651226Y666288D03*
X639940Y687841D03*
X640330Y684439D03*
X642999Y685781D03*
X644950Y719110D03*
X638890Y734879D03*
X652660Y749000D03*
X639920Y753526D03*
X646680Y755009D03*
X646500Y746300D03*
X650400Y770522D03*
X638470Y762212D03*
X649640Y757527D03*
X646370Y759252D03*
X647410Y767053D03*
X651690Y778099D03*
X640010Y778215D03*
X652212Y786700D03*
X655947Y53677D03*
X659947Y53722D03*
X655642Y144915D03*
Y149915D03*
X655695Y159567D03*
Y164567D03*
X655030Y228744D03*
Y223744D03*
X657838Y243407D03*
Y238407D03*
X656270Y299379D03*
X654962Y307698D03*
X654060Y302459D03*
X659350Y298810D03*
X655122Y315070D03*
X656730Y338633D03*
X659543Y377086D03*
X662390Y377039D03*
X653938Y364885D03*
X668925Y364887D03*
X663632Y366698D03*
X669215Y377488D03*
X658295Y417662D03*
X653649Y417582D03*
X668779Y417135D03*
X663674Y417999D03*
X655812Y424106D03*
X663339Y425601D03*
X658339D03*
X664450Y435739D03*
X658680Y446610D03*
X660458Y470932D03*
X659828Y465162D03*
X667774Y477992D03*
X661158Y486152D03*
X667070Y483608D03*
X662780Y477039D03*
X660518Y492862D03*
X662630Y500823D03*
X654240Y511568D03*
X653800Y505331D03*
X659933Y513927D03*
X664024Y513414D03*
X668573Y514155D03*
X668823Y532470D03*
X668627Y527718D03*
X667050Y535324D03*
X655445Y591918D03*
X658980Y610043D03*
X655978Y609635D03*
X656070Y612743D03*
X655688Y601761D03*
X663560Y625019D03*
X659600Y623785D03*
X655873Y615540D03*
X654221Y631425D03*
X657550Y655072D03*
X659978Y666274D03*
X665050Y680648D03*
X657340Y690286D03*
X655610Y706309D03*
X656505Y701191D03*
X657320Y723584D03*
X654050Y718086D03*
X656650Y713057D03*
X659200Y721454D03*
X659300Y734119D03*
X654000Y736400D03*
X655574Y728674D03*
X657570Y730414D03*
X658860Y727383D03*
X656000Y732400D03*
X657500Y761500D03*
X664460Y785890D03*
X657010Y786039D03*
X675927Y53779D03*
X669987Y53672D03*
X676590Y188198D03*
X680100Y188182D03*
X680220Y200725D03*
X678650Y203480D03*
X681770Y203514D03*
X682140Y191214D03*
Y194615D03*
X680310Y217357D03*
X678750Y214908D03*
X681870Y214942D03*
X679590Y352829D03*
X679430Y350013D03*
X677083Y375124D03*
X677946Y387211D03*
X678986Y392661D03*
X679138Y397985D03*
X680017Y403143D03*
X678838Y407785D03*
X673368Y416621D03*
X671056Y426300D03*
X672660Y441007D03*
X673740Y449887D03*
X682764Y444832D03*
X677070Y444820D03*
X672190Y457216D03*
X683112Y479786D03*
X679299Y491473D03*
X684876Y497385D03*
X674156Y503662D03*
X678450Y508438D03*
X680790Y504521D03*
X677160Y529422D03*
X675044Y524581D03*
X684620Y535923D03*
X678217Y536752D03*
X678360Y557426D03*
X673950Y557314D03*
X677850Y562515D03*
X673700D03*
X677730Y567706D03*
X673590Y567696D03*
X670940Y612070D03*
X683720Y631732D03*
X678386Y668420D03*
X673386D03*
X675100Y749300D03*
X672710Y746235D03*
X672500Y749179D03*
X684500Y786665D03*
X676390Y778439D03*
X677490Y782114D03*
X673290Y782855D03*
X677227Y786454D03*
X669320Y783845D03*
X681480Y777388D03*
X681164Y783461D03*
X669810Y786721D03*
X672500Y779579D03*
X683520Y789080D03*
Y792080D03*
X698150Y136791D03*
X687546Y154228D03*
X699990Y149631D03*
X700060Y144981D03*
X693520Y186376D03*
X697850Y186441D03*
X689820Y200159D03*
Y203491D03*
X689480Y191144D03*
Y194615D03*
X691970Y216820D03*
X691690Y212100D03*
X693540Y205721D03*
X697800Y205879D03*
X692010Y221158D03*
X687584Y233034D03*
X686686Y392522D03*
X687869Y386780D03*
X688118Y381043D03*
X686686Y397522D03*
X689527Y407843D03*
X685859Y403970D03*
X691037Y401739D03*
X689527Y412843D03*
X687130Y464132D03*
X691070Y464058D03*
X689017Y497282D03*
X694823Y498932D03*
X692520Y506898D03*
X696494Y513677D03*
X689729Y509580D03*
X696891Y507279D03*
X700719Y516954D03*
X686661Y519199D03*
X698438Y524890D03*
X686770Y543325D03*
X694150Y536155D03*
X690040Y535797D03*
X687183Y539585D03*
X687660Y631799D03*
X685640Y634154D03*
X698386Y667241D03*
X693386D03*
X699600Y776000D03*
X689700Y774500D03*
X711676Y51019D03*
X701770Y331938D03*
X702730Y455483D03*
X704550Y444407D03*
X715528Y459332D03*
X710768Y475972D03*
X715328Y481122D03*
X704766Y498880D03*
X713978Y498075D03*
X716021Y516945D03*
X700829Y504041D03*
X707736Y510140D03*
X707920Y505575D03*
X706361Y532632D03*
X716260Y525295D03*
X712820Y519647D03*
X701170Y538508D03*
X708258Y549815D03*
X713300Y578995D03*
X713190Y583032D03*
X712740Y593101D03*
X712732Y631749D03*
X716064D03*
X713742Y634373D03*
X708386Y669774D03*
X703386D03*
X713445Y677641D03*
X709500Y736800D03*
X704000Y770800D03*
X716245Y765576D03*
X719800Y24920D03*
X726500Y123466D03*
X726400Y130303D03*
X726470Y126659D03*
X726580Y455637D03*
X731570Y464043D03*
X726430Y465371D03*
X726830Y460815D03*
X727940Y469943D03*
X731340Y476723D03*
X720140Y478333D03*
X718431Y483368D03*
X721290Y484381D03*
X719370Y472436D03*
X725730Y486788D03*
X729640Y486848D03*
X727602Y500100D03*
X720150Y491632D03*
X719332Y515757D03*
X719761Y532432D03*
X728661Y558934D03*
X731251Y558975D03*
X726154Y559002D03*
X720445Y558990D03*
X723370Y558906D03*
X719092Y631682D03*
X717372Y634474D03*
X727830Y641829D03*
X728690Y649829D03*
X721100Y689400D03*
X718445Y677641D03*
X731200Y716200D03*
X730800Y728400D03*
X729500Y746300D03*
X721245Y765576D03*
X726925Y778490D03*
X731925D03*
X744760Y103711D03*
X744790Y106938D03*
X747710Y100293D03*
X738370Y123395D03*
X745070Y110183D03*
X738270Y130232D03*
X738340Y126588D03*
X747080Y129815D03*
X747600Y323527D03*
X745220Y327250D03*
X736310Y450774D03*
X737350Y464330D03*
Y459823D03*
X743364Y478975D03*
X743150Y483502D03*
X738130Y502748D03*
X732817Y489435D03*
X734575Y492575D03*
X745500Y492500D03*
X744020Y566143D03*
X744090Y575066D03*
X743951Y578833D03*
X744050Y571834D03*
X747470Y585542D03*
X747460Y582318D03*
X744000Y647919D03*
X733210Y645829D03*
X732540Y653829D03*
X751080Y100293D03*
X754580Y124020D03*
X748070Y110209D03*
X751180D03*
X754610Y127247D03*
X750930Y129815D03*
X750430Y314330D03*
X750350Y311343D03*
X750700Y323771D03*
X753230Y328262D03*
X759400Y334839D03*
X754850Y335055D03*
X755500Y337791D03*
X758494Y455532D03*
X748723Y455332D03*
X758500Y469500D03*
X751730Y583047D03*
X765250Y357789D03*
X765610Y361194D03*
G54D17*
X20859Y109561D03*
X78740Y30708D03*
X73740Y20708D03*
X713661D03*
X708661Y30708D03*
X703661Y20708D03*
X712975Y155655D03*
Y165455D03*
Y173455D03*
Y234461D03*
Y244261D03*
Y252261D03*
X723275Y155655D03*
Y165455D03*
Y173455D03*
Y234461D03*
Y244261D03*
Y252261D03*
G54D46*
X556181Y81889D03*
G54D11*
X-44872Y125213D03*
Y141213D03*
Y232533D03*
D03*
Y248533D03*
D03*
Y738493D03*
Y754493D03*
X-26872Y125213D03*
Y141213D03*
Y232533D03*
D03*
Y248533D03*
D03*
Y738493D03*
Y754493D03*
G54D21*
X36024Y181225D03*
Y205257D03*
Y199249D03*
Y193241D03*
Y217272D03*
Y211264D03*
X41930Y184229D03*
Y202253D03*
Y190237D03*
Y208260D03*
G54D34*
X154038Y511386D03*
X153967Y517186D03*
X162335Y521906D03*
X155400Y533436D03*
X154246Y527468D03*
X162335Y528206D03*
X159186Y534504D03*
X154945Y539233D03*
X159185Y547103D03*
X154900Y548682D03*
X159186Y553402D03*
X157611Y557468D03*
X154410Y557990D03*
X178818Y274540D03*
X178085Y518755D03*
X168617Y525756D03*
X172371Y519783D03*
X174720Y531356D03*
X178117Y528187D03*
X178099Y550267D03*
X174105Y542290D03*
X167027Y539526D03*
Y536376D03*
X173217Y536556D03*
X181818Y274540D03*
X181232Y515607D03*
X187417Y508756D03*
X189007Y514846D03*
X187875Y534128D03*
X181232Y537654D03*
X184384Y543955D03*
X188927Y537836D03*
X190434Y546870D03*
X207309Y539953D03*
X216184Y268587D03*
X223709Y505353D03*
X214118Y528583D03*
X218751Y543835D03*
X233626Y502591D03*
X230476D03*
X243075D03*
X236776Y518339D03*
X233626Y508891D03*
Y515190D03*
X230476D03*
X233626Y518339D03*
X236776Y512040D03*
X243075Y508891D03*
X230476D03*
X236776Y515190D03*
X230476Y518339D03*
Y512040D03*
X239925Y518339D03*
X233626Y521489D03*
Y527788D03*
X230476Y534087D03*
X236776Y521489D03*
Y527788D03*
Y524639D03*
X230476D03*
X233626Y534087D03*
X239925Y527788D03*
Y524639D03*
X230476Y527788D03*
Y521489D03*
X239925Y534087D03*
Y521489D03*
X233626Y543536D03*
X239925Y540386D03*
Y543536D03*
X236776Y537236D03*
X230476D03*
Y543536D03*
Y540386D03*
X233626D03*
X236776Y543536D03*
X233626Y537236D03*
X239925D03*
X243075Y559284D03*
Y552984D03*
X252524Y502591D03*
X255673D03*
X249374D03*
X246224D03*
X255673Y512040D03*
X252524D03*
X255673Y508891D03*
Y505741D03*
X249374D03*
Y508891D03*
X252524Y505741D03*
Y508891D03*
X249374Y512040D03*
X246224D03*
X252524Y549835D03*
X255673D03*
X249374D03*
X246224Y559284D03*
Y556134D03*
Y562434D03*
X252554Y559314D03*
X262904Y293850D03*
X268943Y291086D03*
X274582Y502591D03*
X271402Y499441D03*
X271429Y496295D03*
X261972Y502591D03*
X268272Y512040D03*
X271422D03*
X265121Y508891D03*
X261972D03*
Y505741D03*
X265122Y512040D03*
X261972D03*
X265122Y505741D03*
X268272Y549836D03*
X271421D03*
X265122D03*
X261972D03*
X271421Y552985D03*
X274572Y556142D03*
X287173Y499445D03*
X277712Y502595D03*
X277725Y534092D03*
Y527792D03*
Y521493D03*
Y540391D03*
Y543541D03*
Y537241D03*
X290322Y549841D03*
X280872D03*
X679175Y464038D03*
X674353Y463842D03*
X683112Y464038D03*
Y483723D03*
X683113Y471941D03*
X683112Y487660D03*
X690986Y467975D03*
X687049Y479786D03*
X690986Y483723D03*
X687049Y471912D03*
X698683Y487517D03*
X690986Y487660D03*
X687049D03*
X692955Y502112D03*
X702797Y464038D03*
Y467975D03*
X706734Y471913D03*
Y483723D03*
X710671Y479786D03*
X706734Y475850D03*
X710671Y471913D03*
X702585Y483749D03*
X702797Y471912D03*
Y479786D03*
X706734D03*
G54D37*
X399606Y377165D03*
X413386Y363385D03*
X403543Y367322D03*
Y387008D03*
X413386Y390945D03*
X427166Y377165D03*
X423229Y367322D03*
Y387008D03*
G54D36*
X354348Y38554D03*
X393718D03*
G54D41*
X507489Y281538D03*
G54D51*
X605796Y204845D03*
X611702Y185690D03*
Y178997D03*
Y200690D03*
Y193997D03*
G54D53*
X711575Y143555D03*
Y195355D03*
Y222361D03*
Y274161D03*
X733975Y143555D03*
Y195355D03*
Y222361D03*
Y274161D03*
G54D48*
X590999Y77041D03*
Y84915D03*
Y92789D03*
X615657Y77041D03*
Y84915D03*
Y92789D03*
G54D44*
X524780Y28803D03*
X514780Y38803D03*
X524780D03*
X534780Y28803D03*
X544780D03*
X534780Y38803D03*
X544780D03*
X554780D03*
X587371Y28803D03*
X577371Y38803D03*
X587371D03*
X597371Y28803D03*
X607371D03*
X597371Y38803D03*
X607371D03*
X617371D03*
X639963D03*
X649963Y28803D03*
Y38803D03*
X659963Y28803D03*
X669963D03*
X659963Y38803D03*
X669963D03*
X679963D03*
G54D26*
X65900Y566403D03*
X66181Y562149D03*
X63930Y560181D03*
X66262Y553344D03*
X65989Y578115D03*
X66036Y574901D03*
X63670Y576040D03*
X69766Y582525D03*
X81491Y533191D03*
X80318Y544311D03*
X81585Y536382D03*
X80318Y541026D03*
X112386Y71874D03*
X114072Y480964D03*
X110400Y502223D03*
X110436Y499681D03*
X110472Y496888D03*
X113337Y502080D03*
X113372Y496888D03*
X113301Y499574D03*
X112575Y532934D03*
X113912Y541144D03*
X114005Y544358D03*
X112627Y536697D03*
X130350Y130400D03*
Y134167D03*
X126072Y480864D03*
X122018Y516353D03*
X135640Y134167D03*
X135590Y130449D03*
X139365Y516636D03*
X139402Y513707D03*
X299629Y623877D03*
X318968Y536052D03*
X319135Y591407D03*
X336088Y454511D03*
X325040Y480129D03*
X355150Y486758D03*
X368787Y472998D03*
X374203Y482079D03*
X377284Y473374D03*
X399060Y454322D03*
X399050Y450968D03*
X398800Y462248D03*
Y458058D03*
X405878Y294071D03*
X403130Y418091D03*
X406200Y417755D03*
X405980Y414630D03*
X405930Y411386D03*
X406140Y424766D03*
X406150Y433203D03*
X406530Y440667D03*
X406000Y444755D03*
X402900Y444842D03*
X413733Y490781D03*
X410733D03*
X407733D03*
Y493781D03*
Y496781D03*
Y499781D03*
X410733Y493781D03*
X413733D03*
X410733Y496781D03*
X413733D03*
X410733Y499781D03*
X413733D03*
X402499Y554143D03*
X418597Y273538D03*
X418698Y279631D03*
X418998Y289871D03*
X418718Y301181D03*
X423278Y525160D03*
X428874Y525193D03*
X417520Y525128D03*
X428874Y530627D03*
X417520Y531177D03*
X428745Y536999D03*
X423332Y536763D03*
X417617Y536773D03*
X454263Y77675D03*
X450917Y97566D03*
X452669Y157140D03*
X539438Y250323D03*
X589036Y548825D03*
X596530Y574903D03*
X596495Y578903D03*
X596484Y582903D03*
X596209Y586903D03*
X590898Y597158D03*
X590842Y608112D03*
X591023Y600384D03*
X605362Y609413D03*
X590646Y618751D03*
X609168Y554851D03*
X607077Y566915D03*
X632362Y565543D03*
X636868Y593141D03*
X630768Y593241D03*
X624468D03*
Y612141D03*
X624368Y605941D03*
Y599741D03*
X629868Y612241D03*
X635968D03*
X643012Y565243D03*
X651437Y569676D03*
X643568Y593241D03*
Y612341D03*
Y606641D03*
Y599541D03*
X638470Y639290D03*
X650928D03*
X665170Y595943D03*
X661396Y588900D03*
X664603Y601976D03*
X654645Y627064D03*
X667610Y617197D03*
X655170Y639432D03*
X681310Y666671D03*
X671400Y666151D03*
X685410Y621250D03*
X688340Y621294D03*
X692720Y670540D03*
X698830Y670652D03*
X703570Y673036D03*
X707660Y673204D03*
X713910Y681330D03*
X718510Y681526D03*
X718150Y763015D03*
X721100Y762903D03*
X727570Y775278D03*
X730990Y775334D03*
G54D32*
X130794Y493910D03*
X133731D03*
X128240Y666583D03*
X120909Y674490D03*
X141682Y269829D03*
X150787Y9246D03*
X158181Y11978D03*
X163518Y243987D03*
X162317Y249877D03*
X161918Y254287D03*
X162484Y276599D03*
X161767Y287242D03*
X162181Y303075D03*
X161687Y310355D03*
X162063Y327940D03*
X159564Y328013D03*
X161513Y317143D03*
X159285Y336220D03*
X164418Y348187D03*
X171310Y12450D03*
X180510Y233307D03*
X174138Y243873D03*
X167467Y243242D03*
X171668Y256287D03*
X175118Y274287D03*
X170617Y267326D03*
X175318Y278687D03*
X170510Y275522D03*
X177470Y294933D03*
X180254Y295023D03*
X175162Y293934D03*
X175659Y286984D03*
X176037Y309845D03*
X180254Y310663D03*
X178812Y324259D03*
X180342Y316469D03*
X175330Y318552D03*
X177359Y332553D03*
X174876Y336549D03*
X168110Y350642D03*
X178232Y430642D03*
X178217Y435317D03*
X193677Y243855D03*
X184318Y247612D03*
X194056Y256697D03*
X193735Y265857D03*
X188442Y252643D03*
X184829Y259139D03*
X190918Y277687D03*
X185991Y279041D03*
X186118Y270787D03*
X183698Y285693D03*
X193557Y294428D03*
X187812Y286352D03*
X184812Y292979D03*
X186254Y295023D03*
X194771Y302176D03*
X193812Y308619D03*
X195254Y310663D03*
X184754Y302843D03*
X193313Y325492D03*
X186296Y326366D03*
X192293Y340792D03*
X185195Y332852D03*
X184367Y337792D03*
X192519Y352761D03*
X182877Y430662D03*
X182879Y435312D03*
X212020Y234359D03*
X211935Y244085D03*
X198685Y240785D03*
X211028Y255696D03*
X210333Y265197D03*
X208129Y257519D03*
X206144Y252477D03*
X208289Y263639D03*
X208226Y269697D03*
X201667Y274542D03*
X199509Y278094D03*
X206299Y312598D03*
X209300Y322800D03*
X207310Y330149D03*
X208485Y332356D03*
X200905Y333776D03*
X201489Y336207D03*
Y339107D03*
X198987Y353137D03*
X206657Y356116D03*
X217135Y244085D03*
X227517Y244187D03*
X219772Y252659D03*
X215761Y252833D03*
X224794Y256754D03*
X218153Y260697D03*
Y263697D03*
X223929Y263639D03*
X225199Y281098D03*
X216109Y274139D03*
X212599Y281098D03*
Y290548D03*
X225199Y287398D03*
X212599Y293698D03*
X222049Y290548D03*
X225199Y309448D03*
Y299998D03*
Y303148D03*
X222049Y309448D03*
X212599Y299998D03*
Y303148D03*
X222049Y312598D03*
X218899Y309448D03*
X222049Y303148D03*
X215100Y322700D03*
X217129Y327207D03*
X215085Y325649D03*
X212600Y319100D03*
X217129Y324207D03*
Y336207D03*
X217067Y339542D03*
X217129Y333207D03*
X223010Y344242D03*
X228057Y352837D03*
X222777Y353066D03*
X214888Y352909D03*
X231749Y265139D03*
X241613Y265197D03*
X233904Y252772D03*
X240910Y274742D03*
X233793Y269697D03*
X237799Y290548D03*
Y284248D03*
X231499Y287398D03*
X237800Y299998D03*
X231499Y309448D03*
X241258Y319123D03*
X240692Y344204D03*
X233055Y339936D03*
X230725Y331649D03*
X238084Y355992D03*
X255209Y260639D03*
X255359Y266557D03*
X249433Y257697D03*
X246467Y255442D03*
X257046Y279607D03*
X255205Y272755D03*
X244109Y277996D03*
X250399Y290548D03*
X244099Y284248D03*
X250399D03*
X244099Y293698D03*
X254334Y298728D03*
X247249Y303148D03*
X244118Y309387D03*
X247281Y315727D03*
X248509Y339207D03*
X247218Y333049D03*
X255009Y338318D03*
X259444Y354291D03*
X246265Y355855D03*
X249541Y587156D03*
Y583156D03*
X246639Y608378D03*
Y605778D03*
X249640Y602519D03*
X246639Y624378D03*
Y621778D03*
Y616378D03*
Y613778D03*
X273660Y23037D03*
X273645Y27712D03*
X269620Y243240D03*
X263029Y259139D03*
X265073Y266697D03*
X263029Y265139D03*
X271811Y256687D03*
X271898Y263173D03*
X271944Y278363D03*
X264386Y280407D03*
X265944Y278363D03*
X274886Y272587D03*
X273386Y280407D03*
X270444Y270543D03*
X271886Y272587D03*
X268886D03*
X268944Y278363D03*
X262886Y288227D03*
X264386Y296047D03*
X271811Y303313D03*
X271944Y309643D03*
X262944D03*
X261386Y311687D03*
X262035Y322679D03*
X267883Y325837D03*
X268502Y344181D03*
X263576Y340898D03*
X274701Y333804D03*
X270326Y335795D03*
X269117Y352876D03*
X278305Y23057D03*
X278307Y27707D03*
X278354Y244281D03*
X290154Y244007D03*
X285934Y243931D03*
X282178Y244005D03*
X289254Y255688D03*
X286492Y258364D03*
X283660Y251542D03*
X281954Y255588D03*
X288954Y260788D03*
X276328Y264687D03*
X277886Y272587D03*
X280886D03*
X286010Y276042D03*
X282867Y281142D03*
X279386Y311687D03*
X285890Y311357D03*
X281461Y321744D03*
X280776Y326412D03*
X275660Y338857D03*
X281212Y338079D03*
X290190Y352480D03*
X278943Y346914D03*
X277718Y352687D03*
X282818D03*
X286711Y352668D03*
X283140Y346082D03*
X291066Y590488D03*
Y593088D03*
X300118Y250987D03*
X295910Y266706D03*
X295110Y262961D03*
X295307Y275439D03*
X294510Y280709D03*
X297782Y291966D03*
X295010Y286767D03*
X294888Y304456D03*
X294781Y309788D03*
X295200Y321473D03*
X294596Y328129D03*
X294218Y343587D03*
X294888Y335326D03*
X294618Y348287D03*
X293467Y352442D03*
X299121Y597542D03*
X311420Y250230D03*
X315410Y258656D03*
X313888Y566003D03*
X313141Y550821D03*
X313075Y553755D03*
X313108Y556556D03*
X313275Y559590D03*
X316788Y572903D03*
X316688Y569603D03*
X320367Y618071D03*
X314910Y627222D03*
X317722Y614646D03*
X329260Y603381D03*
X328930Y611691D03*
X383344Y590662D03*
Y593262D03*
X391630Y597900D03*
X410522Y593947D03*
X413022D03*
X412960Y618207D03*
X410315Y614782D03*
X624101Y296525D03*
X640448Y294422D03*
X643170Y294282D03*
X641227Y297070D03*
X644113Y297071D03*
X653352Y291388D03*
X640171Y311965D03*
X644105D03*
X651352Y323938D03*
X653162Y318398D03*
X650162D03*
X638166Y560972D03*
X638286Y557415D03*
X660899Y311515D03*
X654352Y323938D03*
X664870Y614543D03*
X656971Y660492D03*
X671129Y305579D03*
X671166Y302550D03*
X687049Y467975D03*
X698860D03*
Y471912D03*
X690986D03*
Y479786D03*
X687049Y483723D03*
X698860Y479786D03*
Y483723D03*
X752960Y653967D03*
X749520Y658372D03*
G54D38*
X414961Y98622D03*
G54D19*
X23628Y321764D03*
Y338300D03*
X434102Y232640D03*
Y311875D03*
X583913Y69167D03*
X608571D03*
G54D22*
X40749Y150808D03*
Y249194D03*
G54D28*
X76880Y143269D03*
X739968Y29361D03*
G54D33*
X151969Y98622D03*
G54D23*
X43898Y168544D03*
Y231457D03*
G54D40*
X481102Y34528D03*
G54D52*
X688977Y105315D03*
Y719488D03*
G54D30*
X98426Y105512D03*
Y719685D03*
G54D54*
X712975Y183255D03*
Y262061D03*
X723275Y183255D03*
Y262061D03*
G54D27*
X83740Y20708D03*
G54D47*
X590999Y69167D03*
X615657D03*
G54D20*
X36024Y187233D03*
X41930Y178221D03*
Y196245D03*
Y220276D03*
Y214268D03*
G54D29*
X86880Y143269D03*
X749968Y29361D03*
G54D18*
X25439Y303260D03*
Y356804D03*
G54D31*
X102362Y247244D03*
Y349606D03*
X354331Y247244D03*
Y349606D03*
G54D39*
X413386Y377165D03*
G54D25*
X66981Y59390D03*
X62981Y59440D03*
X57040Y73421D03*
X72890Y154349D03*
X81210Y261337D03*
X129860Y14571D03*
X131474Y43439D03*
X137500Y25494D03*
X147461Y38078D03*
X147497Y42983D03*
X145210Y60154D03*
X149157Y60010D03*
X141190Y597685D03*
X145880Y584125D03*
X144710Y598135D03*
X134450Y682978D03*
X134777Y738726D03*
Y734726D03*
X134720Y742382D03*
X153863Y15176D03*
X164139Y13027D03*
X154592Y21173D03*
X152412Y38112D03*
X152366Y42983D03*
X152789Y53124D03*
X161640Y403286D03*
X154307Y507507D03*
X154517Y513931D03*
X159185Y531356D03*
X153731Y520734D03*
X159185Y543953D03*
X155060Y545526D03*
X154945Y542383D03*
Y536083D03*
X162315Y553391D03*
X155109Y561153D03*
X154900Y551832D03*
X151900Y590454D03*
X157963Y643289D03*
X179235Y7369D03*
X171666Y7449D03*
X175280Y12401D03*
X174166Y7449D03*
X166639Y13027D03*
X169149Y50968D03*
X175290Y389582D03*
X174500Y383383D03*
X175993Y414924D03*
X178082Y537654D03*
X171053Y569411D03*
X179532Y600437D03*
X173432D03*
X165832Y600337D03*
Y606037D03*
Y613137D03*
X172532Y619537D03*
X178632Y619437D03*
X165832D03*
X177038Y647135D03*
X166388Y647435D03*
X189235Y7369D03*
X191735D03*
X181735D03*
X190700Y418325D03*
X186417Y518526D03*
X186467Y514036D03*
X184920Y508626D03*
X181232Y528205D03*
Y543953D03*
X184384Y537656D03*
X188383Y556895D03*
X184386Y553406D03*
X185032Y606737D03*
X184932Y600537D03*
X185032Y612937D03*
X184932Y619437D03*
X211760Y610915D03*
X207476Y608936D03*
X207010Y602472D03*
X211862Y617709D03*
X202450Y663633D03*
X216209Y488853D03*
X213209D03*
X224209Y494928D03*
X221591Y563371D03*
X223561Y561475D03*
X218859Y593093D03*
X219296Y604811D03*
X215699Y625977D03*
X215985Y633977D03*
X216107Y637977D03*
X215948Y629977D03*
X231209Y566282D03*
X245609Y517182D03*
X262798Y417886D03*
X267741Y491608D03*
X262009Y556153D03*
X284024Y499445D03*
X303722Y385367D03*
X301209Y488853D03*
X303709Y489353D03*
X307116Y385979D03*
X336057Y575657D03*
X369280Y415600D03*
X374560Y412421D03*
X401670Y93807D03*
X409060Y92095D03*
X468210Y401505D03*
X474130Y553659D03*
X474290Y563565D03*
X486640Y543687D03*
X486720Y563730D03*
X481380Y553210D03*
X481410Y573563D03*
X485890Y590563D03*
X489380Y590839D03*
X582920Y194220D03*
X588692Y192809D03*
X758223Y446532D03*
X757823Y451032D03*
G54D14*
X-35858Y731383D03*
X21881Y595792D03*
X17071Y658951D03*
X33841Y9183D03*
X28104Y30414D03*
X24411Y16186D03*
X34149Y44149D03*
X30282Y34564D03*
X28250Y438740D03*
X37990Y453022D03*
X28250Y472076D03*
X37990Y520218D03*
X38807Y543539D03*
X38349Y555730D03*
X34440Y597285D03*
X36930Y611082D03*
X35862Y617052D03*
X29964Y658951D03*
X45410Y21563D03*
X54860Y16952D03*
X43480Y34592D03*
X45578Y50478D03*
X54703Y122796D03*
X46811Y122928D03*
X54062Y257049D03*
X49244Y360352D03*
X49730Y412473D03*
X45530D03*
X52150Y414896D03*
X47900Y414660D03*
X44360Y414915D03*
X49640Y430237D03*
X45410Y430444D03*
X51350Y433695D03*
X47420Y433725D03*
X44360Y433729D03*
X49625Y478472D03*
Y480972D03*
X50330Y497940D03*
X53330D03*
X49645Y491804D03*
Y489304D03*
X47380Y494638D03*
X53622Y509276D03*
X53330Y506417D03*
Y503817D03*
X50330D03*
X46140Y541712D03*
X43850Y602797D03*
X50170Y636895D03*
X59524Y25922D03*
X68756Y167695D03*
X56190Y170026D03*
X59640Y161376D03*
X57257Y180712D03*
X55963Y199565D03*
X57749Y204326D03*
X56383Y218543D03*
X63720Y228683D03*
X56936Y223944D03*
X57624Y366105D03*
X66747Y466363D03*
X64050Y465689D03*
X61183Y465314D03*
X65438Y510666D03*
X61033Y510705D03*
X61003Y515110D03*
X65478D03*
X56148Y530809D03*
X67260Y546688D03*
X63300Y621755D03*
X63490Y630693D03*
X79360Y46044D03*
X82065Y73224D03*
X80845Y106859D03*
X81030Y172605D03*
X78850Y157866D03*
X82030Y191733D03*
X75236Y188946D03*
X75359Y201109D03*
X85876Y218939D03*
X78190Y214642D03*
X72150Y225148D03*
X78614Y229920D03*
X79217Y232861D03*
X79544Y267579D03*
X82368Y297135D03*
X72368Y287906D03*
X73917Y385722D03*
X74031Y393857D03*
X85951Y410263D03*
X83455Y489485D03*
Y491985D03*
X85955Y489485D03*
Y491985D03*
X83455Y494485D03*
X85955D03*
X81635Y517104D03*
Y513104D03*
X72216Y540493D03*
X73130Y601599D03*
X73180Y611184D03*
X80630Y689682D03*
X82847Y716068D03*
X82736Y791695D03*
Y788695D03*
X70925D03*
Y791695D03*
X97830Y66508D03*
X98531Y121340D03*
X90878Y177967D03*
X86560Y205852D03*
X96168Y231618D03*
X93200Y300734D03*
X99968Y367705D03*
X95968Y367814D03*
X98410Y421908D03*
X98470Y418834D03*
X101650Y428745D03*
Y425552D03*
Y433296D03*
Y436075D03*
X101590Y446203D03*
X101650Y443038D03*
X86726Y501997D03*
X88563Y491984D03*
Y489484D03*
Y494484D03*
X91458Y511853D03*
X98410Y680541D03*
X100223Y733207D03*
X94547Y788695D03*
Y791695D03*
X115628Y104405D03*
X106517Y210796D03*
X110490Y397362D03*
X116960Y394023D03*
X114207Y417910D03*
Y414910D03*
X105670Y411262D03*
X117980Y451981D03*
X118020Y455079D03*
X114372Y518898D03*
X109640Y611890D03*
X109410Y621425D03*
X109500Y616724D03*
X109260Y644687D03*
Y648989D03*
X117790Y667235D03*
X115748Y716275D03*
X114232Y791695D03*
Y788695D03*
X126460Y250160D03*
X126570Y256194D03*
X129660Y279890D03*
X130310Y269174D03*
X123160Y287060D03*
X129610Y287115D03*
X122729Y398001D03*
X127729D03*
X125229D03*
X128226Y413925D03*
X125726D03*
X123226D03*
X121080Y460060D03*
X124040Y459746D03*
X127060Y460040D03*
X121360Y472028D03*
X118720Y471989D03*
X132960Y550005D03*
X125340Y558090D03*
X129607Y686735D03*
X120357Y738889D03*
X120322Y742187D03*
X123518Y742030D03*
X146558Y74863D03*
X147570Y249033D03*
X147160Y242219D03*
X143150Y281123D03*
X137925Y290987D03*
X136130Y305640D03*
X137091Y301799D03*
X135730Y314543D03*
X134768Y319043D03*
X135224Y323543D03*
X136506Y332193D03*
X144058Y376025D03*
X135507Y421367D03*
X147820Y441929D03*
X145020Y576001D03*
X147753Y627557D03*
X145750Y630254D03*
X147750Y687539D03*
X143823Y682907D03*
X134753Y726161D03*
X137070Y728012D03*
X141791Y788695D03*
Y791695D03*
X161221Y89447D03*
X160040Y108844D03*
X162130Y129344D03*
X160449Y259605D03*
X158583Y285548D03*
X161918Y293869D03*
X162017Y324389D03*
X152058Y376016D03*
X160058Y375818D03*
X150524Y382808D03*
X161577Y436834D03*
X161563Y432521D03*
X158430Y568437D03*
X149860Y726626D03*
X177224Y49101D03*
X174724D03*
X177224Y51601D03*
X174724D03*
X172224Y49101D03*
Y54101D03*
X177224D03*
X174724D03*
X172224Y51601D03*
X177757Y88271D03*
X168308Y88412D03*
X180990Y108770D03*
X177210Y97657D03*
X165690Y98835D03*
X171950Y105105D03*
X167127Y120603D03*
X174213Y120569D03*
X171320Y243601D03*
X166189Y335285D03*
X167383Y341306D03*
X177604Y355155D03*
X177720Y352522D03*
X177029Y347811D03*
X177672Y358103D03*
X176058Y376568D03*
X168058Y376035D03*
X167951Y380551D03*
X170506Y424127D03*
X173151Y427552D03*
X172944Y448387D03*
X170444D03*
X179857Y477790D03*
X169293Y562358D03*
X171180Y652009D03*
X171270Y655650D03*
X179180Y675205D03*
X174761Y663816D03*
X178278Y705976D03*
Y701976D03*
Y697976D03*
Y709976D03*
X171689Y728920D03*
X173287Y791695D03*
Y788695D03*
X184843Y88467D03*
X191930Y88507D03*
X196000Y95568D03*
X195473Y108767D03*
X184170Y95213D03*
X186060Y100103D03*
X196010Y125188D03*
X186730Y121202D03*
X188821Y232784D03*
X189192Y243061D03*
X187404Y343998D03*
X186925Y355812D03*
X186908Y352760D03*
X184058Y376479D03*
X194231Y390267D03*
X194330Y396425D03*
X192676Y402961D03*
X182771Y424013D03*
X185271D03*
X182771Y421513D03*
X185271D03*
X192069Y444852D03*
X185747Y487664D03*
X188654Y573395D03*
X188200Y672526D03*
X196463Y685036D03*
X182163Y684555D03*
X194508Y704476D03*
X187798Y704513D03*
X185440Y712499D03*
X196144Y712602D03*
X187744Y708356D03*
X191930Y712624D03*
X194440Y735623D03*
X189940Y735681D03*
X185440D03*
X182674Y730521D03*
X199016Y88434D03*
X206103Y88207D03*
X202560Y107797D03*
X210203Y108457D03*
X206273Y98364D03*
X207070Y179744D03*
X207154Y175212D03*
X207041Y184502D03*
X207070Y188978D03*
X197243Y344518D03*
X206817Y358874D03*
X207274Y353124D03*
X202823Y376922D03*
X200439Y390168D03*
X203880Y385272D03*
X200488Y396425D03*
X200039Y448750D03*
Y451350D03*
X197809Y469953D03*
X200434Y478345D03*
X208710Y500856D03*
X211379Y501904D03*
X208050Y528883D03*
X209886Y539962D03*
X201509Y539853D03*
X199709Y551653D03*
X208109Y551053D03*
X209238Y674373D03*
X210023Y712842D03*
X201663Y712694D03*
X198940Y712499D03*
X212440Y735829D03*
X198940Y735681D03*
X207940D03*
X203440D03*
X200846Y788695D03*
Y791695D03*
X225990Y21219D03*
X221990D03*
X221600Y66317D03*
X225600D03*
X213190Y88414D03*
X220276Y88440D03*
X214573Y93771D03*
X219095Y108675D03*
X217040Y103121D03*
X226713Y122007D03*
X223561Y385108D03*
X214008Y385165D03*
X221438Y390655D03*
X226276Y460704D03*
X213994Y466054D03*
X214626Y516492D03*
X227329Y508894D03*
X216564Y528902D03*
X223453Y578087D03*
X216590Y570850D03*
X220428Y580271D03*
X221129Y642363D03*
X215768Y671993D03*
X224289Y680081D03*
X224360Y684366D03*
X213365Y692151D03*
X226610Y713482D03*
X216940Y736063D03*
X221440Y735934D03*
X225940Y724061D03*
X220532Y788695D03*
Y791695D03*
X212658D03*
Y788695D03*
X241990Y21219D03*
X229990D03*
X237600Y66317D03*
X241600D03*
X229600D03*
X233600D03*
X236360Y93931D03*
X236812Y88698D03*
X229725Y88719D03*
X243730Y103057D03*
X240355Y108757D03*
X239500Y100925D03*
X231910Y105731D03*
X235190Y96905D03*
X233268Y121742D03*
X230749Y160807D03*
X230650Y164566D03*
X230890Y169424D03*
X231000Y173381D03*
X230100Y187389D03*
X230140Y197240D03*
X233697Y353961D03*
X243940Y390885D03*
X236687Y385234D03*
X232172Y388814D03*
X240599Y440053D03*
X242915Y576539D03*
X239269Y597128D03*
X229809Y583627D03*
X229584Y652668D03*
X237451Y652761D03*
X243596Y671772D03*
X229895Y671672D03*
X240493Y692678D03*
X238348Y712469D03*
X243900Y724662D03*
X239440Y736140D03*
X230440Y736412D03*
X234940Y724325D03*
X240217Y788695D03*
Y791695D03*
X232343D03*
Y788695D03*
X249990Y21219D03*
X245990D03*
X257270Y29334D03*
X258300Y22289D03*
X253810Y63244D03*
X245600Y66317D03*
X249600D03*
X246073Y92197D03*
X256573Y94097D03*
X247870Y105821D03*
X250399Y296848D03*
X253611Y293765D03*
X254819Y332435D03*
X250466Y344381D03*
X245691Y341215D03*
X251334Y352857D03*
X250661Y384780D03*
X244196Y419610D03*
Y417010D03*
Y427610D03*
Y425010D03*
Y433010D03*
Y435610D03*
X253709Y586128D03*
X249462Y648383D03*
X257271Y671772D03*
X253398Y692357D03*
X254940Y712381D03*
X253340Y724726D03*
X248440Y736163D03*
X257440Y736041D03*
X252940Y736318D03*
X252028Y791695D03*
X271421Y7319D03*
X268579Y19365D03*
X265934Y16522D03*
X268372Y40782D03*
X265872D03*
X273873Y63167D03*
X269793D03*
X261750Y75886D03*
X274580Y74281D03*
X269920Y74318D03*
X272440Y76177D03*
X268080Y76416D03*
X264210Y96914D03*
X268702Y107928D03*
X267020Y257079D03*
X265886Y271718D03*
X270430Y665576D03*
X269709Y672575D03*
X270140Y691038D03*
X265300Y702131D03*
X275440Y735626D03*
X261940Y735878D03*
X266440Y736030D03*
X270940Y735642D03*
X271713Y788695D03*
Y791695D03*
X259902D03*
X280699Y13908D03*
X278199D03*
X282180Y10253D03*
X285703Y9813D03*
X280699Y16408D03*
X278199D03*
X287476Y37125D03*
X290823Y63167D03*
X282023D03*
X277853D03*
X287270Y75018D03*
X283870Y74724D03*
X279100Y74447D03*
X289738Y76173D03*
X285543Y76867D03*
X281400Y75938D03*
X276969Y76247D03*
X287599Y108831D03*
X278880Y108482D03*
X276507Y295816D03*
X276687Y385100D03*
X283820Y396266D03*
X281142Y402379D03*
X276809Y471853D03*
X276347Y459741D03*
X284332Y472834D03*
X282298Y483803D03*
X289171Y661908D03*
X288880Y689467D03*
X278341Y717269D03*
X279940Y724126D03*
X289240Y724687D03*
X283990Y734977D03*
X279587Y791695D03*
X295307Y41260D03*
X295390Y44017D03*
X295610Y50299D03*
X295560Y52907D03*
X294903Y63167D03*
X306693D03*
X303053D03*
X298883D03*
X292313Y76345D03*
X305880Y76361D03*
X299220Y76196D03*
X302953Y76167D03*
X295867Y76567D03*
X299590Y121289D03*
X299850Y124708D03*
X297668Y300709D03*
X298202Y374572D03*
X301240Y470885D03*
X291327Y466811D03*
X306220Y477125D03*
X296913Y514460D03*
X301457Y513837D03*
X291357Y586128D03*
X305602Y620685D03*
Y618185D03*
X299090Y634421D03*
X305200Y652883D03*
X301696Y701851D03*
Y699351D03*
X291790Y735976D03*
X306540Y724266D03*
X297940Y724377D03*
X302660Y736359D03*
X298160Y736489D03*
X291398Y792234D03*
X299272Y791695D03*
X314640Y63167D03*
X310483D03*
X318543D03*
X322713D03*
X318910Y74595D03*
X314310Y74540D03*
X307740Y74263D03*
X309730Y76232D03*
X316623Y76047D03*
X312402Y76587D03*
X313583Y122387D03*
X321643Y321928D03*
X309143D03*
X311643D03*
X314143D03*
X316643D03*
X319143D03*
X322765Y327721D03*
X322210Y336696D03*
X319323Y338320D03*
X309510Y344127D03*
X319666Y354376D03*
X309131Y374573D03*
X314860Y367656D03*
X315383Y387863D03*
X315533Y384749D03*
X316963Y467655D03*
X316956Y478833D03*
X313347Y570695D03*
X312641Y611556D03*
X307996Y611536D03*
X312656Y606881D03*
X307994Y606886D03*
X308102Y620685D03*
Y618185D03*
X307574Y633762D03*
X314790Y652049D03*
X317130Y653628D03*
X322440Y700130D03*
X320110Y703093D03*
X317580Y719996D03*
X307940Y736445D03*
X311440Y735831D03*
X315940Y735924D03*
X320440Y736031D03*
X311083Y791871D03*
X318957Y791695D03*
X336316Y31815D03*
X326353Y63167D03*
X336024Y88176D03*
X329643Y89887D03*
X336340Y99265D03*
X327950Y101057D03*
X323032Y122237D03*
X331376Y299883D03*
X332700Y333089D03*
X334816Y367787D03*
X337316Y367758D03*
X337330Y372679D03*
X334816Y372609D03*
X325749Y418701D03*
X336218Y424850D03*
X325180Y432577D03*
X323154Y556367D03*
Y558867D03*
Y553867D03*
X337550Y558618D03*
Y556118D03*
Y553618D03*
X325841Y719731D03*
X336990Y735701D03*
X324940Y736067D03*
X329440Y735814D03*
X333940Y735895D03*
X339162Y9304D03*
Y11904D03*
X350411Y21277D03*
X339239Y24232D03*
X339471Y19373D03*
Y16773D03*
X339239Y26832D03*
X350198Y88277D03*
X343111Y88429D03*
X344770Y101718D03*
X351793Y105404D03*
X344073Y124397D03*
X351533Y124697D03*
X351373Y134367D03*
X345297Y284849D03*
X342955Y291523D03*
X354170Y308924D03*
X351500Y301795D03*
X342759Y599193D03*
X339616Y603438D03*
Y605938D03*
X339384Y611544D03*
X339600Y621293D03*
Y618693D03*
X339384Y614144D03*
X353298Y633903D03*
X351728Y653860D03*
X339930Y661219D03*
X340525Y686600D03*
X344780Y713349D03*
X343730Y724581D03*
X350180Y735880D03*
X350580Y724427D03*
X346516Y790294D03*
X358285Y21325D03*
X356550Y74767D03*
X366733Y88477D03*
X359646Y88174D03*
X360827Y108541D03*
X362300Y98674D03*
X367560Y120823D03*
X354580Y298101D03*
X357400Y307608D03*
X362660Y316986D03*
X357110Y329210D03*
X359410Y317080D03*
X359120Y331164D03*
X357040Y332970D03*
X360960Y389080D03*
X368943Y506356D03*
X366426Y527722D03*
Y530222D03*
Y532722D03*
X368238Y522673D03*
X365329Y546121D03*
X368694Y546159D03*
X367858Y657573D03*
X365070Y658065D03*
X362173Y665128D03*
X367399Y684652D03*
X367866Y677326D03*
X361646Y689228D03*
X364844Y698332D03*
X361786Y699128D03*
X361717Y695128D03*
X366510Y723622D03*
X361350Y720720D03*
X361490Y712505D03*
X363162Y739537D03*
X366430Y731459D03*
X357096Y732976D03*
X360246Y730819D03*
X363359Y743537D03*
X366201Y787976D03*
X354390Y790294D03*
X366201Y790976D03*
X379940Y17789D03*
X382990Y17519D03*
X380906Y88134D03*
X373820Y88400D03*
X384450Y108830D03*
X372620Y98355D03*
X384090Y98743D03*
X379160Y102923D03*
X374030Y95000D03*
X377363Y121108D03*
X376150Y430405D03*
X373850Y496585D03*
X379177Y509798D03*
X383924Y514797D03*
X385040Y521754D03*
X384588Y526069D03*
X382632Y530322D03*
Y527822D03*
Y532822D03*
X384485Y552365D03*
X382595Y554166D03*
X385573Y629998D03*
X371407Y641507D03*
X380101Y660239D03*
X375575Y739459D03*
X370430Y749138D03*
X376960Y788580D03*
Y791580D03*
X399002Y17519D03*
X393371Y72919D03*
X399804Y88778D03*
X397442Y90667D03*
X389400Y89232D03*
X399653Y108357D03*
X391536Y108990D03*
X398820Y95823D03*
X391190Y104173D03*
X388860Y98010D03*
X399150Y131773D03*
X391880Y131692D03*
X399858Y249711D03*
X399298Y257231D03*
X391998Y258251D03*
X392668Y272511D03*
X400928Y293151D03*
X396098Y283931D03*
X389107Y492097D03*
X400589Y611672D03*
X400587Y607022D03*
X398195Y620821D03*
X400695Y618321D03*
X398195D03*
X400695Y620821D03*
X392063Y624109D03*
X396940Y658078D03*
X396478Y661529D03*
X399911Y661325D03*
X400267Y684029D03*
X390000Y689724D03*
X389961Y682218D03*
X389350Y711288D03*
X414949Y75291D03*
X403739Y72783D03*
X404528Y88702D03*
X405688Y253581D03*
X405038Y267521D03*
X401728Y277251D03*
X409054Y483084D03*
X412260Y482881D03*
X405234Y611692D03*
X405249Y607017D03*
X405426Y626809D03*
X413930Y639810D03*
X410989Y652957D03*
X415834Y693272D03*
X409581Y711643D03*
X413940Y735665D03*
X421473Y160556D03*
Y157556D03*
X422698Y244301D03*
X422288Y250661D03*
X419038Y242611D03*
X427768Y253569D03*
X422178Y266891D03*
X428208Y262109D03*
X426948Y281051D03*
X422918Y289501D03*
X419071Y509283D03*
X422210Y605343D03*
X419221Y612253D03*
X422221Y619873D03*
X422470Y647852D03*
X425146Y672426D03*
X430140Y665660D03*
X417974Y663446D03*
X422510Y677836D03*
X430873Y684536D03*
X425173Y688588D03*
X423317Y705344D03*
X422940Y723802D03*
X420160Y724309D03*
X430940Y735895D03*
X426430Y735126D03*
X418440Y735930D03*
X421321Y791476D03*
X417384D03*
X446268Y69074D03*
X446088Y90159D03*
Y85159D03*
Y87659D03*
X434158Y122272D03*
X443448Y124552D03*
X441518Y122242D03*
X434158Y125092D03*
X444828Y122132D03*
X433253Y160737D03*
X433363Y157607D03*
X442580Y236459D03*
X447900Y265292D03*
X442148Y279361D03*
X442165Y271284D03*
X441076Y294906D03*
X441361Y300812D03*
X437887Y471073D03*
X437516Y587579D03*
X440135Y615808D03*
X433872Y645119D03*
X446980Y638774D03*
X446799Y657526D03*
X444403Y665963D03*
X446900Y714648D03*
X447240Y724780D03*
X439940Y735507D03*
X443940Y735681D03*
X435440Y735928D03*
X436440Y724710D03*
X441006Y791476D03*
X437069D03*
X450618Y69004D03*
X457583Y66384D03*
X462294Y87759D03*
Y85259D03*
Y90259D03*
X453298Y122254D03*
X450798D03*
X452158Y124582D03*
X458818Y122065D03*
Y125422D03*
X455292Y162797D03*
X455470Y166963D03*
X455913Y178698D03*
X452115Y195057D03*
X450576Y234431D03*
X454150Y249053D03*
X457165Y262368D03*
X449290Y276227D03*
X453780Y292411D03*
X461130Y408318D03*
X461080Y411451D03*
X463690Y451813D03*
X461590Y446700D03*
X461540Y449833D03*
X457702Y475480D03*
X460702D03*
X454702D03*
X463702D03*
X450899Y483452D03*
X460236Y581679D03*
X458600Y599200D03*
X453775Y600614D03*
X453935Y624739D03*
X456342Y649436D03*
X458650Y666543D03*
X463120Y681992D03*
X460530Y681874D03*
X459650Y685993D03*
X457730Y682010D03*
X456960Y685581D03*
X461960Y684394D03*
X453530Y736212D03*
X458050Y725053D03*
X462440Y735687D03*
X460691Y791476D03*
X456754D03*
X464767Y78145D03*
X466647Y91224D03*
X466682Y102410D03*
X474381Y125310D03*
X478088Y125219D03*
X474140Y408318D03*
X469590D03*
X465330D03*
X474080Y411451D03*
X469530D03*
X465270D03*
X480050Y419556D03*
X471540Y437214D03*
X473140Y439971D03*
X469500Y447730D03*
X467920Y451667D03*
X472210Y450267D03*
X465730Y449833D03*
X465790Y446700D03*
X479575Y467597D03*
X479754Y462988D03*
X466702Y475480D03*
X473153Y622451D03*
X478905Y659426D03*
X470190Y648693D03*
X479353Y668666D03*
X466049Y675327D03*
X471450Y736368D03*
X466440Y735987D03*
X471310Y733811D03*
X466440Y724465D03*
X474940Y747192D03*
X476439Y791476D03*
X488438Y100123D03*
X484068Y99980D03*
X490760Y154771D03*
X495300Y201600D03*
X491046Y207506D03*
X486738Y210434D03*
X488816Y242877D03*
X495140Y385762D03*
X486670Y426196D03*
X483685Y473522D03*
X483641Y479628D03*
X489938Y563425D03*
X490658Y579025D03*
X487398Y576665D03*
X490693Y570770D03*
X490538Y567825D03*
X485380Y596505D03*
X491100Y644351D03*
X491930Y654203D03*
X495622Y660178D03*
X491157Y675604D03*
X491189Y679656D03*
X494323Y687669D03*
X496000Y736152D03*
X483180Y736506D03*
X487940Y735681D03*
X491890Y735740D03*
X494850Y733252D03*
X480376Y791476D03*
X508904Y124063D03*
X502132Y146686D03*
X498875Y217172D03*
X499075Y235575D03*
X496123Y233500D03*
X504897Y390481D03*
X505819Y417473D03*
X510577Y417741D03*
X498238Y417825D03*
X502687Y417453D03*
X499551Y429636D03*
X502494Y436725D03*
X509464Y450265D03*
X505442Y458719D03*
X511070Y493380D03*
X511520Y496255D03*
X505740Y495880D03*
X511560Y513792D03*
X504613Y522050D03*
X500138Y543225D03*
X503448Y540235D03*
X505718Y542865D03*
X500038Y555925D03*
Y550725D03*
X510338Y571325D03*
X499868Y585725D03*
X505738Y600425D03*
X496140Y608883D03*
X504268Y608625D03*
X498666Y653012D03*
X502890Y736349D03*
X506105Y724132D03*
X500061Y791476D03*
X496124D03*
X518248Y137692D03*
X518477Y141401D03*
X527349Y152246D03*
X526875Y161838D03*
X511997Y207730D03*
X519183Y224173D03*
X519300Y220500D03*
X516625Y230075D03*
X517617Y422944D03*
X514820Y417617D03*
X526440Y432077D03*
X515780Y434039D03*
X513140Y452621D03*
X519440Y452321D03*
X526340D03*
X513140Y459721D03*
Y466021D03*
X525640Y473021D03*
X519640D03*
X513140D03*
X516353Y480708D03*
X519490Y496645D03*
X525698Y496724D03*
X522250Y513692D03*
X527138Y529525D03*
X523938Y528725D03*
X515110Y528785D03*
X519438Y543025D03*
X513480Y541499D03*
X513838Y556925D03*
X512354Y590825D03*
X519638Y600425D03*
X523538Y600325D03*
X527438D03*
X519830Y634663D03*
X515371Y658880D03*
X515425Y685783D03*
X518500Y723073D03*
X519440Y735681D03*
X512140Y736554D03*
X514901Y724120D03*
X523370Y724131D03*
X519746Y791476D03*
X515809D03*
X542248Y106333D03*
X527898Y147146D03*
X533483Y177449D03*
X533797Y180764D03*
X536676Y234993D03*
X536576Y246993D03*
X529527Y265584D03*
X529910Y419478D03*
X541440Y431787D03*
X536440Y431923D03*
X531440Y432178D03*
X542738Y455823D03*
X530038Y444323D03*
X533040Y453221D03*
X533740Y458021D03*
Y465021D03*
X542738Y463123D03*
X533740Y473021D03*
X540938Y473623D03*
X535729Y476632D03*
X539419Y491107D03*
X532934Y491384D03*
X530638Y539525D03*
X534638Y539825D03*
X541238Y539625D03*
X533038Y590325D03*
X536438Y600425D03*
X542438Y613723D03*
X538400Y613804D03*
X540048Y629641D03*
X535230Y648711D03*
X535485Y715182D03*
X537702Y735662D03*
X541940Y735681D03*
X528440D03*
X531845Y724095D03*
X539431Y791476D03*
X535494D03*
X547248Y106582D03*
X548367Y135415D03*
X548007Y139415D03*
X547543Y143415D03*
X558845Y158697D03*
X558768Y191223D03*
X553909Y207401D03*
X547927Y212190D03*
X558416Y210682D03*
X544700Y216100D03*
X547148Y220220D03*
X555707Y389146D03*
X543381Y448428D03*
X556771Y456156D03*
X556959Y443009D03*
X551140Y445789D03*
X556971Y460656D03*
X547340Y484025D03*
X548000Y509493D03*
X547880Y515743D03*
X544138Y530125D03*
X545413Y547950D03*
X551438Y561225D03*
X551538Y568525D03*
X550938Y587325D03*
X548138Y600425D03*
X544638Y600525D03*
X553619Y601204D03*
X546938Y613828D03*
X552849Y631652D03*
X545377Y647594D03*
X547346Y697581D03*
X544984Y699419D03*
X555148Y735583D03*
X550940Y735681D03*
X546440D03*
X555179Y791476D03*
X561909Y207393D03*
X571576Y246693D03*
X564676D03*
X571476Y260093D03*
X564676D03*
Y253693D03*
X567320Y415088D03*
X561610Y503885D03*
X560960Y510151D03*
X571830Y509411D03*
X567791Y528325D03*
X568068Y525306D03*
X561065Y543998D03*
X560838Y540325D03*
X574738Y579525D03*
X574537Y591325D03*
X574738Y587425D03*
X574645Y583525D03*
X565168Y684614D03*
X568215Y702343D03*
X568288Y715547D03*
X568908Y735883D03*
X573440Y735681D03*
X564438Y735853D03*
X560350Y735807D03*
X573440Y724053D03*
X568940Y724090D03*
X562395Y724557D03*
X559116Y791476D03*
X578938Y103123D03*
X583829Y117732D03*
X583661Y121836D03*
X584438Y160933D03*
X579707Y220662D03*
X578076Y246693D03*
Y253393D03*
Y260093D03*
X575874Y282395D03*
Y289895D03*
Y285995D03*
X583853Y313783D03*
X585584Y308881D03*
X579168Y313641D03*
X583737Y321204D03*
X575550Y463784D03*
X575650Y469996D03*
X579600Y508878D03*
X585013Y547959D03*
X575438Y545425D03*
X575238Y552025D03*
X575038Y567725D03*
X575538Y571725D03*
X574876Y575625D03*
X586369Y585801D03*
X579500Y625963D03*
X587440Y656958D03*
X576700Y655594D03*
X584903Y663828D03*
X586060Y682582D03*
X587040Y688218D03*
X586995Y694080D03*
X583440Y735856D03*
X587940Y735681D03*
X587963Y724108D03*
X577940Y724127D03*
X578802Y791476D03*
X574864D03*
X594920Y123370D03*
X592491Y175906D03*
X595707Y220995D03*
X597074Y239995D03*
X600874Y239795D03*
X604774Y249795D03*
X596774D03*
X600874D03*
X604674Y239995D03*
X592874Y250995D03*
X605674Y236295D03*
X596574Y268695D03*
X600674Y268795D03*
X604574D03*
X604926Y278476D03*
X604774Y271893D03*
X592201Y308988D03*
X591977Y319360D03*
X605746Y387837D03*
X605573Y393920D03*
X605798Y501238D03*
X596751Y532108D03*
X605521Y601097D03*
X594733Y653385D03*
X601588Y664798D03*
X592440Y723768D03*
X596860Y723422D03*
X601440Y735681D03*
X605938Y735665D03*
X596940Y735681D03*
X593004Y735662D03*
X598487Y791476D03*
X594550D03*
X618623Y108918D03*
X608274Y249795D03*
X608774Y239995D03*
X608274Y268795D03*
X613640Y336986D03*
X608869Y396959D03*
X608821Y403445D03*
X621760Y526967D03*
X609300Y531638D03*
X613541Y546764D03*
X614579Y645072D03*
X610651Y675156D03*
X614909Y671938D03*
X617235Y689036D03*
X621410Y696941D03*
X607020Y704644D03*
X611244Y709830D03*
X621254Y713788D03*
X617093Y709167D03*
X619590Y735383D03*
X614732Y735517D03*
X608791Y735775D03*
X618172Y791476D03*
X614235D03*
X610298D03*
X624358Y176090D03*
X632483Y192781D03*
X624950Y189801D03*
X632485Y202077D03*
X633633Y403717D03*
X633663Y411009D03*
X634945Y461888D03*
X635545Y465888D03*
X622199Y506535D03*
X634190Y538267D03*
X634251Y683493D03*
X623940Y723503D03*
X623960Y735141D03*
X628380Y735476D03*
X629983Y791476D03*
X633920D03*
X638970Y132241D03*
X646013Y358110D03*
X647440Y386383D03*
X647340Y393283D03*
X647440Y408383D03*
X647340Y400083D03*
X651138Y417385D03*
X641480Y430289D03*
X650079D03*
X646381Y478679D03*
X646105Y492010D03*
X646906Y505210D03*
X648077Y713569D03*
X653500Y732583D03*
X639928Y738905D03*
X658769Y143630D03*
X658767Y151013D03*
X658959Y165625D03*
X658972Y158337D03*
X667300Y188112D03*
X660700Y203282D03*
X669250Y203317D03*
X665320Y203247D03*
X664560Y195018D03*
Y191443D03*
X660770Y214951D03*
X665390Y214916D03*
X661160Y235485D03*
X658582Y222614D03*
X658601Y229770D03*
X661190Y246085D03*
X666270Y359134D03*
X660138Y365885D03*
X654340Y386283D03*
X661140D03*
X654840Y408483D03*
X661940Y408383D03*
X666312Y417742D03*
X656021Y427864D03*
X665766Y427868D03*
X664528Y463432D03*
X667428D03*
X666928Y468132D03*
X659740Y536019D03*
X668000Y676595D03*
X656254Y683277D03*
X663040Y688057D03*
X654514Y720674D03*
X656660Y736218D03*
X661479Y791476D03*
X665416D03*
X679927Y53881D03*
X670980Y77061D03*
X671810Y106472D03*
X670280Y188112D03*
X669320Y214986D03*
X672752Y366160D03*
X679552Y372873D03*
X669540Y386283D03*
X678099Y389915D03*
X674235Y379364D03*
X669440Y395183D03*
Y408483D03*
X669540Y402783D03*
X678338Y405185D03*
X683128Y451332D03*
X680228Y451432D03*
X670428Y463532D03*
X669728Y468032D03*
X672628D03*
X678315Y540752D03*
X669390Y695406D03*
X672630Y720752D03*
X688160Y64459D03*
X689500Y120441D03*
X691148Y140140D03*
X691280Y149571D03*
X691314Y145071D03*
X687571Y172292D03*
X687584Y251770D03*
X689864Y392130D03*
X687121Y407004D03*
X689864Y398141D03*
X686731Y413349D03*
X691161Y518684D03*
X691532Y559789D03*
Y563789D03*
Y567789D03*
Y571789D03*
Y575789D03*
Y579789D03*
Y583789D03*
Y587789D03*
X695600Y590788D03*
X689100Y680291D03*
X688510Y735294D03*
X707176Y50574D03*
X706380Y75482D03*
X708130Y106389D03*
X701687Y212132D03*
X700947Y216868D03*
X700994Y221368D03*
X707942Y448676D03*
X714639Y454872D03*
X712239Y452293D03*
X712281Y525785D03*
X710585Y539103D03*
X701023Y553658D03*
X710873Y563230D03*
X715282Y620282D03*
X711612Y620383D03*
X708450Y695489D03*
X705870Y721832D03*
X706575Y740425D03*
X704786Y791274D03*
X708723Y791092D03*
X709040Y787507D03*
X726160Y109316D03*
X726190Y105325D03*
X726160Y112508D03*
X731566Y442136D03*
X729942Y515757D03*
X720052Y620480D03*
X729500Y737400D03*
X721790Y791408D03*
X722590Y787885D03*
X738620Y109351D03*
X738650Y105360D03*
X738620Y112543D03*
X741401Y454832D03*
X742779Y487639D03*
X734460Y788654D03*
Y791654D03*
X762590Y106529D03*
X762630Y103302D03*
X757500Y474000D03*
X748300Y496800D03*
X766840Y561290D03*
X766920Y564080D03*
X766950Y558318D03*
X766820Y569897D03*
X766900Y567233D03*
Y572869D03*
X771110Y578643D03*
X770850Y575760D03*
X770710Y584054D03*
X770850Y587025D03*
G54D35*
X227326Y505741D03*
X230476D03*
X236776Y508891D03*
X252524Y527789D03*
Y524639D03*
X255673Y534088D03*
X252524D03*
X249374D03*
X255673Y524639D03*
Y527789D03*
X249374D03*
Y524639D03*
X255673Y537237D03*
X249374D03*
X252524D03*
X255673Y540387D03*
X249374D03*
X252524D03*
X255673Y565580D03*
Y552984D03*
Y556133D03*
Y559282D03*
Y562431D03*
X249344Y552984D03*
Y556134D03*
X265122Y502591D03*
X268272Y505741D03*
Y508891D03*
X261972Y521489D03*
X268272Y534088D03*
X265122D03*
X261972D03*
X268272Y524639D03*
Y527789D03*
X265122D03*
Y524639D03*
X261972D03*
Y527789D03*
X268272Y521489D03*
X265122D03*
X268272Y540387D03*
X265122D03*
X261972D03*
X265122Y537237D03*
X268272D03*
X261972D03*
X274571Y552985D03*
X265122D03*
X268272Y559291D03*
X271422Y562434D03*
X271421Y556135D03*
X271422Y559291D03*
X261973Y552985D03*
X261972Y562431D03*
X271422Y565583D03*
X290323Y534092D03*
X280874D03*
X287174D03*
X284024D03*
X280874Y537241D03*
Y543541D03*
X284024D03*
X287174Y540391D03*
Y543541D03*
X290323Y540391D03*
Y543541D03*
X287174Y559289D03*
X290323Y565589D03*
X284024Y565588D03*
X287174D03*
X290323Y559289D03*
Y562439D03*
Y556140D03*
X287174Y562438D03*
X280874D03*
X284024D03*
Y559289D03*
X277725Y552989D03*
X280874Y559289D03*
X277725Y556135D03*
Y559289D03*
X287174Y556139D03*
X280874Y552989D03*
X284024Y556139D03*
X287174Y552989D03*
X284024D03*
X293473Y534092D03*
Y540391D03*
Y565589D03*
Y562439D03*
Y559290D03*
G54D50*
X605796Y174845D03*
Y189845D03*
G54D16*
X10859Y109561D03*
G54D42*
X507489Y360278D03*
G54D45*
X546181Y81889D03*
G54D43*
X514780Y28803D03*
X554780D03*
X577371D03*
X617371D03*
X639963D03*
X679963D03*
G54D49*
X605796Y165160D03*
X609733Y215672D03*
G54D24*
X45282Y321764D03*
Y338300D03*
%LPC*%
G75*
G36*
G01X-36897Y131113D02*
G02X-34847I1025J-400D01*
G01X-33897D01*
G02Y130313I1025J-400D01*
G01X-34847D01*
G02X-36897I-1025J400D01*
G01X-37847D01*
G02Y131113I-1025J400D01*
G01X-36897D01*
G37*
G36*
G01Y238433D02*
G02X-34847I1025J-400D01*
G01X-33897D01*
G02Y237633I1025J-400D01*
G01X-34847D01*
G02X-36897I-1025J400D01*
G01X-37847D01*
G02Y238433I-1025J400D01*
G01X-36897D01*
G37*
G36*
G01X-34847D02*
G03X-36897I-1025J-400D01*
G01X-37847D01*
G03Y237633I-1025J-400D01*
G01X-36897D01*
G03X-34847I1025J400D01*
G01X-33897D01*
G03Y238433I1025J400D01*
G01X-34847D01*
G37*
G36*
G01Y748593D02*
G02X-36897I-1025J400D01*
G01X-37847D01*
G02Y749393I-1025J400D01*
G01X-36897D01*
G02X-34847I1025J-400D01*
G01X-33897D01*
G02Y748593I1025J-400D01*
G01X-34847D01*
G37*
G54D55*
G01X38493Y-241864D02*
Y-246864D01*
G01X37036Y-241864D02*
X39950D01*
G01X44860Y-246864D02*
X42326D01*
Y-241864D01*
X44860D01*
G01X43846Y-244281D02*
X42326D01*
G01X47426Y-241864D02*
Y-246864D01*
X49960D01*
G01X53793Y-247031D02*
X53666Y-246947D01*
Y-246781D01*
X53793Y-246697D01*
X53920Y-246781D01*
Y-246947D01*
X53793Y-247031D01*
G01Y-244781D02*
X53666Y-244697D01*
Y-244531D01*
X53793Y-244447D01*
X53920Y-244531D01*
Y-244697D01*
X53793Y-244781D01*
G01X58576Y-248531D02*
X57943Y-247697D01*
X57626Y-246864D01*
Y-243531D01*
X57943Y-242697D01*
X58576Y-241864D01*
G01X63993D02*
X63486Y-242031D01*
X63106Y-242447D01*
X62853Y-242947D01*
X62663Y-243614D01*
X62600Y-244364D01*
X62663Y-245114D01*
X62853Y-245781D01*
X63106Y-246281D01*
X63486Y-246697D01*
X63993Y-246864D01*
X64500Y-246697D01*
X64880Y-246281D01*
X65133Y-245781D01*
X65323Y-245114D01*
X65386Y-244364D01*
X65323Y-243614D01*
X65133Y-242947D01*
X64880Y-242447D01*
X64500Y-242031D01*
X63993Y-241864D01*
G01X67700Y-245864D02*
X68080Y-246447D01*
X68586Y-246781D01*
X69156Y-246864D01*
X69663Y-246781D01*
X70170Y-246364D01*
X70486Y-245864D01*
X70550Y-245364D01*
X70423Y-244781D01*
X69980Y-244364D01*
X69536Y-244197D01*
X68966D01*
G01X69536D02*
X69916Y-243947D01*
X70233Y-243531D01*
X70360Y-243031D01*
X70233Y-242531D01*
X69916Y-242114D01*
X69346Y-241864D01*
X68776Y-241947D01*
X68206Y-242281D01*
G01X74510Y-248531D02*
X75143Y-247697D01*
X75460Y-246864D01*
Y-243531D01*
X75143Y-242697D01*
X74510Y-241864D01*
G01X77900Y-245864D02*
X78280Y-246447D01*
X78786Y-246781D01*
X79356Y-246864D01*
X79863Y-246781D01*
X80370Y-246364D01*
X80686Y-245864D01*
X80750Y-245364D01*
X80623Y-244781D01*
X80180Y-244364D01*
X79736Y-244197D01*
X79166D01*
G01X79736D02*
X80116Y-243947D01*
X80433Y-243531D01*
X80560Y-243031D01*
X80433Y-242531D01*
X80116Y-242114D01*
X79546Y-241864D01*
X78976Y-241947D01*
X78406Y-242281D01*
G01X83190Y-242697D02*
X83570Y-242197D01*
X84013Y-241947D01*
X84520Y-241864D01*
X85153Y-242031D01*
X85596Y-242447D01*
X85723Y-242947D01*
X85660Y-243447D01*
X85406Y-243864D01*
X84140Y-244697D01*
X83570Y-245281D01*
X83190Y-246114D01*
X83063Y-246864D01*
X85723D01*
G01X89366D02*
X89493Y-245781D01*
X89683Y-244864D01*
X89936Y-244031D01*
X90253Y-243114D01*
X90760Y-241864D01*
X88226D01*
G01X93770Y-245197D02*
X95416D01*
G01X98490Y-242697D02*
X98870Y-242197D01*
X99313Y-241947D01*
X99820Y-241864D01*
X100453Y-242031D01*
X100896Y-242447D01*
X101023Y-242947D01*
X100960Y-243447D01*
X100706Y-243864D01*
X99440Y-244697D01*
X98870Y-245281D01*
X98490Y-246114D01*
X98363Y-246864D01*
X101023D01*
G01X103400Y-245864D02*
X103780Y-246447D01*
X104286Y-246781D01*
X104856Y-246864D01*
X105363Y-246781D01*
X105870Y-246364D01*
X106186Y-245864D01*
X106250Y-245364D01*
X106123Y-244781D01*
X105680Y-244364D01*
X105236Y-244197D01*
X104666D01*
G01X105236D02*
X105616Y-243947D01*
X105933Y-243531D01*
X106060Y-243031D01*
X105933Y-242531D01*
X105616Y-242114D01*
X105046Y-241864D01*
X104476Y-241947D01*
X103906Y-242281D01*
G01X110653Y-246864D02*
Y-241864D01*
X108310Y-245447D01*
X111476D01*
G01X113600Y-246114D02*
X113980Y-246531D01*
X114423Y-246781D01*
X114993Y-246864D01*
X115563Y-246697D01*
X116006Y-246364D01*
X116323Y-245781D01*
X116386Y-245114D01*
X116260Y-244447D01*
X115943Y-244031D01*
X115500Y-243697D01*
X115056Y-243614D01*
X114613Y-243697D01*
X114043Y-244031D01*
X114233Y-241864D01*
X115943D01*
G01X123990Y-246864D02*
Y-241864D01*
X126396D01*
G01X125510Y-244281D02*
X123990D01*
G01X128710Y-246864D02*
X130293Y-241864D01*
X131876Y-246864D01*
G01X131306Y-245114D02*
X129280D01*
G01X134063Y-246864D02*
X136723Y-241864D01*
G01X134063D02*
X136723Y-246864D01*
G01X140493Y-247031D02*
X140366Y-246947D01*
Y-246781D01*
X140493Y-246697D01*
X140620Y-246781D01*
Y-246947D01*
X140493Y-247031D01*
G01Y-244781D02*
X140366Y-244697D01*
Y-244531D01*
X140493Y-244447D01*
X140620Y-244531D01*
Y-244697D01*
X140493Y-244781D01*
G01X145276Y-248531D02*
X144643Y-247697D01*
X144326Y-246864D01*
Y-243531D01*
X144643Y-242697D01*
X145276Y-241864D01*
G01X150693D02*
X150186Y-242031D01*
X149806Y-242447D01*
X149553Y-242947D01*
X149363Y-243614D01*
X149300Y-244364D01*
X149363Y-245114D01*
X149553Y-245781D01*
X149806Y-246281D01*
X150186Y-246697D01*
X150693Y-246864D01*
X151200Y-246697D01*
X151580Y-246281D01*
X151833Y-245781D01*
X152023Y-245114D01*
X152086Y-244364D01*
X152023Y-243614D01*
X151833Y-242947D01*
X151580Y-242447D01*
X151200Y-242031D01*
X150693Y-241864D01*
G01X154400Y-245864D02*
X154780Y-246447D01*
X155286Y-246781D01*
X155856Y-246864D01*
X156363Y-246781D01*
X156870Y-246364D01*
X157186Y-245864D01*
X157250Y-245364D01*
X157123Y-244781D01*
X156680Y-244364D01*
X156236Y-244197D01*
X155666D01*
G01X156236D02*
X156616Y-243947D01*
X156933Y-243531D01*
X157060Y-243031D01*
X156933Y-242531D01*
X156616Y-242114D01*
X156046Y-241864D01*
X155476Y-241947D01*
X154906Y-242281D01*
G01X161210Y-248531D02*
X161843Y-247697D01*
X162160Y-246864D01*
Y-243531D01*
X161843Y-242697D01*
X161210Y-241864D01*
G01X164600Y-245864D02*
X164980Y-246447D01*
X165486Y-246781D01*
X166056Y-246864D01*
X166563Y-246781D01*
X167070Y-246364D01*
X167386Y-245864D01*
X167450Y-245364D01*
X167323Y-244781D01*
X166880Y-244364D01*
X166436Y-244197D01*
X165866D01*
G01X166436D02*
X166816Y-243947D01*
X167133Y-243531D01*
X167260Y-243031D01*
X167133Y-242531D01*
X166816Y-242114D01*
X166246Y-241864D01*
X165676Y-241947D01*
X165106Y-242281D01*
G01X170016Y-246281D02*
X170460Y-246697D01*
X170966Y-246864D01*
X171473Y-246697D01*
X171916Y-246197D01*
X172233Y-245447D01*
X172360Y-244697D01*
Y-243781D01*
X172233Y-243031D01*
X171916Y-242364D01*
X171536Y-242031D01*
X171093Y-241864D01*
X170586Y-242031D01*
X170206Y-242364D01*
X169953Y-242864D01*
X169826Y-243531D01*
X169953Y-244114D01*
X170270Y-244697D01*
X170650Y-245031D01*
X171093Y-245114D01*
X171600Y-244947D01*
X171980Y-244531D01*
X172360Y-243781D01*
G01X176066Y-246864D02*
X176193Y-245781D01*
X176383Y-244864D01*
X176636Y-244031D01*
X176953Y-243114D01*
X177460Y-241864D01*
X174926D01*
G01X180470Y-245197D02*
X182116D01*
G01X185000Y-245864D02*
X185380Y-246447D01*
X185886Y-246781D01*
X186456Y-246864D01*
X186963Y-246781D01*
X187470Y-246364D01*
X187786Y-245864D01*
X187850Y-245364D01*
X187723Y-244781D01*
X187280Y-244364D01*
X186836Y-244197D01*
X186266D01*
G01X186836D02*
X187216Y-243947D01*
X187533Y-243531D01*
X187660Y-243031D01*
X187533Y-242531D01*
X187216Y-242114D01*
X186646Y-241864D01*
X186076Y-241947D01*
X185506Y-242281D01*
G01X190290Y-244781D02*
X190733Y-244197D01*
X191113Y-243864D01*
X191620Y-243697D01*
X192063Y-243864D01*
X192380Y-244197D01*
X192633Y-244697D01*
X192696Y-245281D01*
X192633Y-245781D01*
X192380Y-246281D01*
X192000Y-246697D01*
X191556Y-246864D01*
X191050Y-246697D01*
X190606Y-246197D01*
X190353Y-245447D01*
X190290Y-244614D01*
X190416Y-243531D01*
X190606Y-242947D01*
X190923Y-242364D01*
X191366Y-241947D01*
X191810Y-241864D01*
X192253Y-242031D01*
X192570Y-242447D01*
G01X196593Y-246864D02*
Y-241864D01*
X195833Y-242864D01*
G01Y-246864D02*
X197353D01*
G01X202453D02*
Y-241864D01*
X200110Y-245447D01*
X203276D01*
G01X26493Y-176864D02*
Y-251864D01*
X526493D01*
Y-176864D01*
X26493D01*
G01X221493D02*
Y-251864D01*
G01Y-226864D02*
X324493D01*
Y-201864D01*
G01X221493D02*
X324493D01*
G01X332000Y-236864D02*
Y-231864D01*
X333266D01*
X333773Y-232114D01*
X334153Y-232447D01*
X334470Y-232947D01*
X334723Y-233531D01*
X334786Y-234364D01*
X334723Y-235197D01*
X334470Y-235781D01*
X334153Y-236281D01*
X333773Y-236614D01*
X333266Y-236864D01*
X332000D01*
G01X336910D02*
X338493Y-231864D01*
X340076Y-236864D01*
G01X339506Y-235114D02*
X337480D01*
G01X343593Y-231864D02*
Y-236864D01*
G01X342136Y-231864D02*
X345050D01*
G01X349960Y-236864D02*
X347426D01*
Y-231864D01*
X349960D01*
G01X348946Y-234281D02*
X347426D01*
G01X353793Y-237031D02*
X353666Y-236947D01*
Y-236781D01*
X353793Y-236697D01*
X353920Y-236781D01*
Y-236947D01*
X353793Y-237031D01*
G01Y-234781D02*
X353666Y-234697D01*
Y-234531D01*
X353793Y-234447D01*
X353920Y-234531D01*
Y-234697D01*
X353793Y-234781D01*
G01X326493Y-176864D02*
Y-251864D01*
G01X324493Y-176864D02*
Y-251864D01*
G01X326493Y-226864D02*
X526493D01*
G01X332126Y-211864D02*
Y-206864D01*
X333646D01*
X334153Y-207114D01*
X334533Y-207697D01*
X334660Y-208364D01*
X334533Y-209031D01*
X334216Y-209531D01*
X333646Y-209781D01*
X332126D01*
G01X337353Y-212031D02*
X339633Y-206864D01*
G01X342136Y-211864D02*
Y-206864D01*
X345050Y-211864D01*
Y-206864D01*
G01X348693Y-212031D02*
X348566Y-211947D01*
Y-211781D01*
X348693Y-211697D01*
X348820Y-211781D01*
Y-211947D01*
X348693Y-212031D01*
G01Y-209781D02*
X348566Y-209697D01*
Y-209531D01*
X348693Y-209447D01*
X348820Y-209531D01*
Y-209697D01*
X348693Y-209781D01*
G01X326493Y-201864D02*
X526493D01*
G01X332126Y-186864D02*
Y-181864D01*
X333646D01*
X334153Y-182114D01*
X334533Y-182697D01*
X334660Y-183364D01*
X334533Y-184031D01*
X334216Y-184531D01*
X333646Y-184781D01*
X332126D01*
G01X337226Y-186864D02*
Y-181864D01*
X338810D01*
X339316Y-182114D01*
X339633Y-182447D01*
X339760Y-183114D01*
X339633Y-183781D01*
X339253Y-184197D01*
X338810Y-184447D01*
X337226D01*
G01X338810D02*
X339760Y-186864D01*
G01X343593D02*
X343086Y-186781D01*
X342643Y-186447D01*
X342263Y-185947D01*
X342010Y-185364D01*
X341883Y-184697D01*
Y-184031D01*
X342010Y-183364D01*
X342263Y-182781D01*
X342643Y-182281D01*
X343086Y-181947D01*
X343593Y-181864D01*
X344100Y-181947D01*
X344543Y-182281D01*
X344923Y-182781D01*
X345176Y-183364D01*
X345303Y-184031D01*
Y-184697D01*
X345176Y-185364D01*
X344923Y-185947D01*
X344543Y-186447D01*
X344100Y-186781D01*
X343593Y-186864D01*
G01X347426Y-185864D02*
X347743Y-186364D01*
X348123Y-186697D01*
X348566Y-186864D01*
X349073Y-186697D01*
X349453Y-186364D01*
X349833Y-185864D01*
X349960Y-185197D01*
Y-181864D01*
G01X355060Y-186864D02*
X352526D01*
Y-181864D01*
X355060D01*
G01X354046Y-184281D02*
X352526D01*
G01X360286Y-182281D02*
X359906Y-182031D01*
X359463Y-181864D01*
X358956D01*
X358386Y-182114D01*
X357943Y-182531D01*
X357626Y-183031D01*
X357373Y-183864D01*
X357310Y-184614D01*
X357436Y-185364D01*
X357626Y-185864D01*
X358006Y-186364D01*
X358450Y-186697D01*
X358893Y-186864D01*
X359336D01*
X359780Y-186697D01*
X360160Y-186447D01*
X360476Y-186114D01*
G01X363993Y-181864D02*
Y-186864D01*
G01X362536Y-181864D02*
X365450D01*
G01X369093Y-187031D02*
X368966Y-186947D01*
Y-186781D01*
X369093Y-186697D01*
X369220Y-186781D01*
Y-186947D01*
X369093Y-187031D01*
G01Y-184781D02*
X368966Y-184697D01*
Y-184531D01*
X369093Y-184447D01*
X369220Y-184531D01*
Y-184697D01*
X369093Y-184781D01*
G01X447126Y-236864D02*
Y-231864D01*
X448710D01*
X449216Y-232114D01*
X449533Y-232447D01*
X449660Y-233114D01*
X449533Y-233781D01*
X449153Y-234197D01*
X448710Y-234447D01*
X447126D01*
G01X448710D02*
X449660Y-236864D01*
G01X454760D02*
X452226D01*
Y-231864D01*
X454760D01*
G01X453746Y-234281D02*
X452226D01*
G01X457010Y-231864D02*
X458593Y-236864D01*
X460176Y-231864D01*
G01X463693Y-237031D02*
X463566Y-236947D01*
Y-236781D01*
X463693Y-236697D01*
X463820Y-236781D01*
Y-236947D01*
X463693Y-237031D01*
G01Y-234781D02*
X463566Y-234697D01*
Y-234531D01*
X463693Y-234447D01*
X463820Y-234531D01*
Y-234697D01*
X463693Y-234781D01*
G01X441493Y-226864D02*
Y-251864D01*
G01X490493Y-226864D02*
Y-251864D01*
G01X-1043962Y-705877D02*
Y2342823D01*
X2300638D01*
Y-705877D01*
X-1043962D01*
G01X37198Y-238524D02*
X37825Y-239049D01*
X38530Y-239364D01*
X39156D01*
X39783Y-239049D01*
X40253Y-238524D01*
X40488Y-237789D01*
X40331Y-237054D01*
X39940Y-236424D01*
X39235Y-236004D01*
X38295Y-235794D01*
X37746Y-235374D01*
X37511Y-234639D01*
X37668Y-233904D01*
X38060Y-233379D01*
X38608Y-233064D01*
X39156D01*
X39705Y-233274D01*
X40175Y-233799D01*
G01X43498Y-239364D02*
Y-233064D01*
G01X46788D02*
Y-239364D01*
G01Y-236214D02*
X43498D01*
G01X50503Y-233064D02*
X52383D01*
G01X51443D02*
Y-239364D01*
G01X50503D02*
X52383D01*
G01X59310D02*
X56176D01*
Y-233064D01*
X59310D01*
G01X58056Y-236109D02*
X56176D01*
G01X62241Y-239364D02*
Y-233064D01*
X65845Y-239364D01*
Y-233064D01*
G01X70186Y-240519D02*
X70500Y-239154D01*
G01X76643Y-233064D02*
Y-239364D01*
G01X74841Y-233064D02*
X78445D01*
G01X80985Y-239364D02*
X82943Y-233064D01*
X84901Y-239364D01*
G01X84196Y-237159D02*
X81690D01*
G01X88303Y-233064D02*
X90183D01*
G01X89243D02*
Y-239364D01*
G01X88303D02*
X90183D01*
G01X93193Y-233064D02*
X94290Y-239364D01*
X95543Y-233064D01*
X96796Y-239364D01*
X97893Y-233064D01*
G01X99885Y-239364D02*
X101843Y-233064D01*
X103801Y-239364D01*
G01X103096Y-237159D02*
X100590D01*
G01X106341Y-239364D02*
Y-233064D01*
X109945Y-239364D01*
Y-233064D01*
G01X119176Y-239364D02*
Y-233064D01*
X121135D01*
X121761Y-233379D01*
X122153Y-233799D01*
X122310Y-234639D01*
X122153Y-235479D01*
X121683Y-236004D01*
X121135Y-236319D01*
X119176D01*
G01X121135D02*
X122310Y-239364D01*
G01X127043Y-239574D02*
X126886Y-239469D01*
Y-239259D01*
X127043Y-239154D01*
X127200Y-239259D01*
Y-239469D01*
X127043Y-239574D01*
G01X133343Y-239364D02*
X132716Y-239259D01*
X132168Y-238839D01*
X131698Y-238209D01*
X131385Y-237474D01*
X131228Y-236634D01*
Y-235794D01*
X131385Y-234954D01*
X131698Y-234219D01*
X132168Y-233589D01*
X132716Y-233169D01*
X133343Y-233064D01*
X133970Y-233169D01*
X134518Y-233589D01*
X134988Y-234219D01*
X135301Y-234954D01*
X135458Y-235794D01*
Y-236634D01*
X135301Y-237474D01*
X134988Y-238209D01*
X134518Y-238839D01*
X133970Y-239259D01*
X133343Y-239364D01*
G01X139643Y-239574D02*
X139486Y-239469D01*
Y-239259D01*
X139643Y-239154D01*
X139800Y-239259D01*
Y-239469D01*
X139643Y-239574D01*
G01X147666Y-233589D02*
X147196Y-233274D01*
X146648Y-233064D01*
X146021D01*
X145316Y-233379D01*
X144768Y-233904D01*
X144376Y-234534D01*
X144063Y-235584D01*
X143985Y-236529D01*
X144141Y-237474D01*
X144376Y-238104D01*
X144846Y-238734D01*
X145395Y-239154D01*
X145943Y-239364D01*
X146491D01*
X147040Y-239154D01*
X147510Y-238839D01*
X147901Y-238419D01*
G01X152243Y-239574D02*
X152086Y-239469D01*
Y-239259D01*
X152243Y-239154D01*
X152400Y-239259D01*
Y-239469D01*
X152243Y-239574D01*
G01X37120Y-229364D02*
Y-223064D01*
G01X40096D02*
X37120Y-226949D01*
G01X40566Y-229364D02*
X38451Y-225164D01*
G01X43420Y-223064D02*
Y-227579D01*
X43733Y-228524D01*
X44360Y-229154D01*
X45143Y-229364D01*
X45926Y-229154D01*
X46553Y-228524D01*
X46866Y-227579D01*
Y-223064D01*
G01X53010Y-229364D02*
X49876D01*
Y-223064D01*
X53010D01*
G01X51756Y-226109D02*
X49876D01*
G01X56803Y-223064D02*
X58683D01*
G01X57743D02*
Y-229364D01*
G01X56803D02*
X58683D01*
G01X68698Y-228524D02*
X69325Y-229049D01*
X70030Y-229364D01*
X70656D01*
X71283Y-229049D01*
X71753Y-228524D01*
X71988Y-227789D01*
X71831Y-227054D01*
X71440Y-226424D01*
X70735Y-226004D01*
X69795Y-225794D01*
X69246Y-225374D01*
X69011Y-224639D01*
X69168Y-223904D01*
X69560Y-223379D01*
X70108Y-223064D01*
X70656D01*
X71205Y-223274D01*
X71675Y-223799D01*
G01X74998Y-229364D02*
Y-223064D01*
G01X78288D02*
Y-229364D01*
G01Y-226214D02*
X74998D01*
G01X80985Y-229364D02*
X82943Y-223064D01*
X84901Y-229364D01*
G01X84196Y-227159D02*
X81690D01*
G01X87441Y-229364D02*
Y-223064D01*
X91045Y-229364D01*
Y-223064D01*
G01X100198Y-229364D02*
Y-223064D01*
G01X103488D02*
Y-229364D01*
G01Y-226214D02*
X100198D01*
G01X106498Y-228524D02*
X107125Y-229049D01*
X107830Y-229364D01*
X108456D01*
X109083Y-229049D01*
X109553Y-228524D01*
X109788Y-227789D01*
X109631Y-227054D01*
X109240Y-226424D01*
X108535Y-226004D01*
X107595Y-225794D01*
X107046Y-225374D01*
X106811Y-224639D01*
X106968Y-223904D01*
X107360Y-223379D01*
X107908Y-223064D01*
X108456D01*
X109005Y-223274D01*
X109475Y-223799D01*
G01X113503Y-223064D02*
X115383D01*
G01X114443D02*
Y-229364D01*
G01X113503D02*
X115383D01*
G01X118785D02*
X120743Y-223064D01*
X122701Y-229364D01*
G01X121996Y-227159D02*
X119490D01*
G01X125241Y-229364D02*
Y-223064D01*
X128845Y-229364D01*
Y-223064D01*
G01X133813Y-226214D02*
X135380D01*
Y-228104D01*
X134910Y-228734D01*
X134361Y-229154D01*
X133578Y-229364D01*
X132795Y-229154D01*
X132246Y-228734D01*
X131776Y-228104D01*
X131463Y-227369D01*
X131306Y-226529D01*
Y-225794D01*
X131463Y-225164D01*
X131776Y-224429D01*
X132246Y-223799D01*
X132716Y-223379D01*
X133343Y-223064D01*
X133891D01*
X134518Y-223274D01*
X134988Y-223694D01*
G01X139486Y-230519D02*
X139800Y-229154D01*
G01X145943Y-223064D02*
Y-229364D01*
G01X144141Y-223064D02*
X147745D01*
G01X150285Y-229364D02*
X152243Y-223064D01*
X154201Y-229364D01*
G01X153496Y-227159D02*
X150990D01*
G01X158543Y-229364D02*
X157916Y-229259D01*
X157368Y-228839D01*
X156898Y-228209D01*
X156585Y-227474D01*
X156428Y-226634D01*
Y-225794D01*
X156585Y-224954D01*
X156898Y-224219D01*
X157368Y-223589D01*
X157916Y-223169D01*
X158543Y-223064D01*
X159170Y-223169D01*
X159718Y-223589D01*
X160188Y-224219D01*
X160501Y-224954D01*
X160658Y-225794D01*
Y-226634D01*
X160501Y-227474D01*
X160188Y-228209D01*
X159718Y-228839D01*
X159170Y-229259D01*
X158543Y-229364D01*
G01X171143D02*
Y-226529D01*
X169576Y-223064D01*
G01X172710D02*
X171143Y-226529D01*
G01X175720Y-223064D02*
Y-227579D01*
X176033Y-228524D01*
X176660Y-229154D01*
X177443Y-229364D01*
X178226Y-229154D01*
X178853Y-228524D01*
X179166Y-227579D01*
Y-223064D01*
G01X181785Y-229364D02*
X183743Y-223064D01*
X185701Y-229364D01*
G01X184996Y-227159D02*
X182490D01*
G01X188241Y-229364D02*
Y-223064D01*
X191845Y-229364D01*
Y-223064D01*
G01X37041Y-219364D02*
Y-213064D01*
X40645Y-219364D01*
Y-213064D01*
G01X45143Y-219364D02*
X44516Y-219259D01*
X43968Y-218839D01*
X43498Y-218209D01*
X43185Y-217474D01*
X43028Y-216634D01*
Y-215794D01*
X43185Y-214954D01*
X43498Y-214219D01*
X43968Y-213589D01*
X44516Y-213169D01*
X45143Y-213064D01*
X45770Y-213169D01*
X46318Y-213589D01*
X46788Y-214219D01*
X47101Y-214954D01*
X47258Y-215794D01*
Y-216634D01*
X47101Y-217474D01*
X46788Y-218209D01*
X46318Y-218839D01*
X45770Y-219259D01*
X45143Y-219364D01*
G01X51443Y-219574D02*
X51286Y-219469D01*
Y-219259D01*
X51443Y-219154D01*
X51600Y-219259D01*
Y-219469D01*
X51443Y-219574D01*
G01X57743Y-219364D02*
Y-213064D01*
X56803Y-214324D01*
G01Y-219364D02*
X58683D01*
G01X64043D02*
X64591Y-219259D01*
X65218Y-218944D01*
X65610Y-218419D01*
X65766Y-217684D01*
X65610Y-216949D01*
X65140Y-216319D01*
X64435Y-216004D01*
X63651D01*
X63181Y-215794D01*
X62790Y-215269D01*
X62633Y-214534D01*
X62868Y-213799D01*
X63416Y-213274D01*
X64043Y-213064D01*
X64670Y-213274D01*
X65218Y-213799D01*
X65453Y-214534D01*
X65296Y-215269D01*
X64905Y-215794D01*
X64435Y-216004D01*
X63651D01*
X62946Y-216319D01*
X62476Y-216949D01*
X62320Y-217684D01*
X62476Y-218419D01*
X62868Y-218944D01*
X63495Y-219259D01*
X64043Y-219364D01*
G01X70343D02*
X70891Y-219259D01*
X71518Y-218944D01*
X71910Y-218419D01*
X72066Y-217684D01*
X71910Y-216949D01*
X71440Y-216319D01*
X70735Y-216004D01*
X69951D01*
X69481Y-215794D01*
X69090Y-215269D01*
X68933Y-214534D01*
X69168Y-213799D01*
X69716Y-213274D01*
X70343Y-213064D01*
X70970Y-213274D01*
X71518Y-213799D01*
X71753Y-214534D01*
X71596Y-215269D01*
X71205Y-215794D01*
X70735Y-216004D01*
X69951D01*
X69246Y-216319D01*
X68776Y-216949D01*
X68620Y-217684D01*
X68776Y-218419D01*
X69168Y-218944D01*
X69795Y-219259D01*
X70343Y-219364D01*
G01X76486Y-220519D02*
X76800Y-219154D01*
G01X80593Y-213064D02*
X81690Y-219364D01*
X82943Y-213064D01*
X84196Y-219364D01*
X85293Y-213064D01*
G01X90810Y-219364D02*
X87676D01*
Y-213064D01*
X90810D01*
G01X89556Y-216109D02*
X87676D01*
G01X93741Y-219364D02*
Y-213064D01*
X97345Y-219364D01*
Y-213064D01*
G01X106498Y-219364D02*
Y-213064D01*
G01X109788D02*
Y-219364D01*
G01Y-216214D02*
X106498D01*
G01X112093Y-213064D02*
X113190Y-219364D01*
X114443Y-213064D01*
X115696Y-219364D01*
X116793Y-213064D01*
G01X118785Y-219364D02*
X120743Y-213064D01*
X122701Y-219364D01*
G01X121996Y-217159D02*
X119490D01*
G01X131855Y-214114D02*
X132325Y-213484D01*
X132873Y-213169D01*
X133500Y-213064D01*
X134283Y-213274D01*
X134831Y-213799D01*
X134988Y-214429D01*
X134910Y-215059D01*
X134596Y-215584D01*
X133030Y-216634D01*
X132325Y-217369D01*
X131855Y-218419D01*
X131698Y-219364D01*
X134988D01*
G01X137841D02*
Y-213064D01*
X141445Y-219364D01*
Y-213064D01*
G01X144220Y-219364D02*
Y-213064D01*
X145786D01*
X146413Y-213379D01*
X146883Y-213799D01*
X147275Y-214429D01*
X147588Y-215164D01*
X147666Y-216214D01*
X147588Y-217264D01*
X147275Y-217999D01*
X146883Y-218629D01*
X146413Y-219049D01*
X145786Y-219364D01*
X144220D01*
G01X156976D02*
Y-213064D01*
X158935D01*
X159561Y-213379D01*
X159953Y-213799D01*
X160110Y-214639D01*
X159953Y-215479D01*
X159483Y-216004D01*
X158935Y-216319D01*
X156976D01*
G01X158935D02*
X160110Y-219364D01*
G01X163120D02*
Y-213064D01*
X164686D01*
X165313Y-213379D01*
X165783Y-213799D01*
X166175Y-214429D01*
X166488Y-215164D01*
X166566Y-216214D01*
X166488Y-217264D01*
X166175Y-217999D01*
X165783Y-218629D01*
X165313Y-219049D01*
X164686Y-219364D01*
X163120D01*
G01X171143Y-219574D02*
X170986Y-219469D01*
Y-219259D01*
X171143Y-219154D01*
X171300Y-219259D01*
Y-219469D01*
X171143Y-219574D01*
G01X61143Y-206664D02*
X58623Y-206247D01*
X56418Y-204581D01*
X54528Y-202081D01*
X53268Y-199164D01*
X52638Y-195831D01*
Y-192497D01*
X53268Y-189164D01*
X54528Y-186247D01*
X56418Y-183748D01*
X58623Y-182081D01*
X61143Y-181664D01*
X63663Y-182081D01*
X65868Y-183748D01*
X67758Y-186247D01*
X69018Y-189164D01*
X69648Y-192497D01*
Y-195831D01*
X69018Y-199164D01*
X67758Y-202081D01*
X65868Y-204581D01*
X63663Y-206247D01*
X61143Y-206664D01*
G01X63663Y-199997D02*
X67443Y-206664D01*
G01X80988Y-189998D02*
Y-201664D01*
X82248Y-204581D01*
X84138Y-206247D01*
X86343Y-206664D01*
X88548Y-206247D01*
X90438Y-204581D01*
X91698Y-201664D01*
G01Y-206664D02*
Y-189998D01*
G01X117213Y-206664D02*
Y-189998D01*
G01Y-192914D02*
X115953Y-191248D01*
X114063Y-190414D01*
X111858Y-189998D01*
X109653Y-190831D01*
X107763Y-192497D01*
X106503Y-194998D01*
X105873Y-198331D01*
X106503Y-201664D01*
X107763Y-204165D01*
X109653Y-205831D01*
X111858Y-206664D01*
X114063Y-206247D01*
X115953Y-204998D01*
X117213Y-203331D01*
G01X131388Y-206664D02*
Y-189998D01*
G01Y-194164D02*
X132648Y-192081D01*
X134538Y-190414D01*
X137058Y-189998D01*
X139263Y-190414D01*
X141153Y-192081D01*
X142098Y-194998D01*
Y-206664D01*
G01X161943Y-181664D02*
Y-206664D01*
G01X157533Y-189998D02*
X166353D01*
G01X192813Y-206664D02*
Y-189998D01*
G01Y-192914D02*
X191553Y-191248D01*
X189663Y-190414D01*
X187458Y-189998D01*
X185253Y-190831D01*
X183363Y-192497D01*
X182103Y-194998D01*
X181473Y-198331D01*
X182103Y-201664D01*
X183363Y-204165D01*
X185253Y-205831D01*
X187458Y-206664D01*
X189663Y-206247D01*
X191553Y-204998D01*
X192813Y-203331D01*
G01X232493Y-186364D02*
Y-194364D01*
X236493D01*
G01X244293D02*
Y-189031D01*
G01Y-189964D02*
X243893Y-189431D01*
X243293Y-189164D01*
X242593Y-189031D01*
X241893Y-189297D01*
X241293Y-189831D01*
X240893Y-190631D01*
X240693Y-191697D01*
X240893Y-192764D01*
X241293Y-193564D01*
X241893Y-194097D01*
X242593Y-194364D01*
X243293Y-194231D01*
X243893Y-193831D01*
X244293Y-193298D01*
G01X248393Y-196764D02*
X248993Y-197031D01*
X249793Y-196764D01*
X250293Y-196231D01*
X250693Y-195564D01*
X251293Y-193431D01*
X252593Y-189031D01*
G01X249393D02*
X251293Y-193431D01*
G01X256993Y-190764D02*
X260193D01*
X259893Y-189831D01*
X259393Y-189297D01*
X258693Y-189031D01*
X257993Y-189164D01*
X257393Y-189564D01*
X256993Y-190497D01*
X256793Y-191298D01*
Y-192097D01*
X256993Y-192897D01*
X257493Y-193697D01*
X258093Y-194231D01*
X258793Y-194364D01*
X259493Y-194097D01*
X260193Y-193298D01*
G01X265093Y-194364D02*
Y-189031D01*
G01Y-190097D02*
X265593Y-189564D01*
X266093Y-189164D01*
X266793Y-189031D01*
X267293Y-189164D01*
X267893Y-189564D01*
G01X254793Y-236364D02*
X257193D01*
G01X255993D02*
Y-244364D01*
G01X254793D02*
X257193D01*
G01X262593D02*
Y-239031D01*
G01Y-240097D02*
X263093Y-239564D01*
X263593Y-239164D01*
X264293Y-239031D01*
X264793Y-239164D01*
X265393Y-239564D01*
G01X270493Y-240764D02*
X273693D01*
X273393Y-239831D01*
X272893Y-239297D01*
X272193Y-239031D01*
X271493Y-239164D01*
X270893Y-239564D01*
X270493Y-240497D01*
X270293Y-241298D01*
Y-242097D01*
X270493Y-242897D01*
X270993Y-243697D01*
X271593Y-244231D01*
X272293Y-244364D01*
X272993Y-244097D01*
X273693Y-243298D01*
G01X278293Y-244364D02*
Y-239031D01*
G01Y-240364D02*
X278693Y-239697D01*
X279293Y-239164D01*
X280093Y-239031D01*
X280793Y-239164D01*
X281393Y-239697D01*
X281693Y-240631D01*
Y-244364D01*
G01X286493Y-240764D02*
X289693D01*
X289393Y-239831D01*
X288893Y-239297D01*
X288193Y-239031D01*
X287493Y-239164D01*
X286893Y-239564D01*
X286493Y-240497D01*
X286293Y-241298D01*
Y-242097D01*
X286493Y-242897D01*
X286993Y-243697D01*
X287593Y-244231D01*
X288293Y-244364D01*
X288993Y-244097D01*
X289693Y-243298D01*
G01X261593Y-215364D02*
X263593D01*
Y-217764D01*
X262993Y-218564D01*
X262293Y-219097D01*
X261293Y-219364D01*
X260293Y-219097D01*
X259593Y-218564D01*
X258993Y-217764D01*
X258593Y-216831D01*
X258393Y-215764D01*
Y-214831D01*
X258593Y-214031D01*
X258993Y-213097D01*
X259593Y-212297D01*
X260193Y-211764D01*
X260993Y-211364D01*
X261693D01*
X262493Y-211631D01*
X263093Y-212164D01*
G01X266693Y-219364D02*
Y-211364D01*
X271293Y-219364D01*
Y-211364D01*
G01X274793Y-219364D02*
Y-211364D01*
X276793D01*
X277593Y-211764D01*
X278193Y-212297D01*
X278693Y-213097D01*
X279093Y-214031D01*
X279193Y-215364D01*
X279093Y-216697D01*
X278693Y-217631D01*
X278193Y-218431D01*
X277593Y-218964D01*
X276793Y-219364D01*
X274793D01*
G01X284993D02*
Y-211364D01*
X283793Y-212964D01*
G01Y-219364D02*
X286193D01*
G01X284093Y-187697D02*
X284693Y-186897D01*
X285393Y-186497D01*
X286193Y-186364D01*
X287193Y-186631D01*
X287893Y-187297D01*
X288093Y-188097D01*
X287993Y-188898D01*
X287593Y-189564D01*
X285593Y-190897D01*
X284693Y-191831D01*
X284093Y-193164D01*
X283893Y-194364D01*
X288093D01*
G01X359093Y-237697D02*
X359693Y-236897D01*
X360393Y-236497D01*
X361193Y-236364D01*
X362193Y-236631D01*
X362893Y-237297D01*
X363093Y-238097D01*
X362993Y-238898D01*
X362593Y-239564D01*
X360593Y-240897D01*
X359693Y-241831D01*
X359093Y-243164D01*
X358893Y-244364D01*
X363093D01*
G01X368993Y-236364D02*
X368193Y-236631D01*
X367593Y-237297D01*
X367193Y-238097D01*
X366893Y-239164D01*
X366793Y-240364D01*
X366893Y-241564D01*
X367193Y-242631D01*
X367593Y-243431D01*
X368193Y-244097D01*
X368993Y-244364D01*
X369793Y-244097D01*
X370393Y-243431D01*
X370793Y-242631D01*
X371093Y-241564D01*
X371193Y-240364D01*
X371093Y-239164D01*
X370793Y-238097D01*
X370393Y-237297D01*
X369793Y-236631D01*
X368993Y-236364D01*
G01X376993Y-244364D02*
Y-236364D01*
X375793Y-237964D01*
G01Y-244364D02*
X378193D01*
G01X383093Y-237697D02*
X383693Y-236897D01*
X384393Y-236497D01*
X385193Y-236364D01*
X386193Y-236631D01*
X386893Y-237297D01*
X387093Y-238097D01*
X386993Y-238898D01*
X386593Y-239564D01*
X384593Y-240897D01*
X383693Y-241831D01*
X383093Y-243164D01*
X382893Y-244364D01*
X387093D01*
G01X391193Y-244631D02*
X394793Y-236364D01*
G01X400993Y-244364D02*
Y-236364D01*
X399793Y-237964D01*
G01Y-244364D02*
X402193D01*
G01X408993Y-236364D02*
X408193Y-236631D01*
X407593Y-237297D01*
X407193Y-238097D01*
X406893Y-239164D01*
X406793Y-240364D01*
X406893Y-241564D01*
X407193Y-242631D01*
X407593Y-243431D01*
X408193Y-244097D01*
X408993Y-244364D01*
X409793Y-244097D01*
X410393Y-243431D01*
X410793Y-242631D01*
X411093Y-241564D01*
X411193Y-240364D01*
X411093Y-239164D01*
X410793Y-238097D01*
X410393Y-237297D01*
X409793Y-236631D01*
X408993Y-236364D01*
G01X415193Y-244631D02*
X418793Y-236364D01*
G01X422793Y-242764D02*
X423393Y-243697D01*
X424193Y-244231D01*
X425093Y-244364D01*
X425893Y-244231D01*
X426693Y-243564D01*
X427193Y-242764D01*
X427293Y-241964D01*
X427093Y-241031D01*
X426393Y-240364D01*
X425693Y-240097D01*
X424793D01*
G01X425693D02*
X426293Y-239697D01*
X426793Y-239031D01*
X426993Y-238231D01*
X426793Y-237431D01*
X426293Y-236764D01*
X425393Y-236364D01*
X424493Y-236497D01*
X423593Y-237031D01*
G01X432993Y-244364D02*
Y-236364D01*
X431793Y-237964D01*
G01Y-244364D02*
X434193D01*
G01X358793Y-219364D02*
Y-211364D01*
X360793D01*
X361593Y-211764D01*
X362193Y-212297D01*
X362693Y-213097D01*
X363093Y-214031D01*
X363193Y-215364D01*
X363093Y-216697D01*
X362693Y-217631D01*
X362193Y-218431D01*
X361593Y-218964D01*
X360793Y-219364D01*
X358793D01*
G01X366493D02*
X368993Y-211364D01*
X371493Y-219364D01*
G01X370593Y-216564D02*
X367393D01*
G01X376993Y-211364D02*
Y-219364D01*
G01X374693Y-211364D02*
X379293D01*
G01X383093Y-216031D02*
X383793Y-215097D01*
X384393Y-214564D01*
X385193Y-214297D01*
X385893Y-214564D01*
X386393Y-215097D01*
X386793Y-215897D01*
X386893Y-216831D01*
X386793Y-217631D01*
X386393Y-218431D01*
X385793Y-219097D01*
X385093Y-219364D01*
X384293Y-219097D01*
X383593Y-218298D01*
X383193Y-217097D01*
X383093Y-215764D01*
X383293Y-214031D01*
X383593Y-213097D01*
X384093Y-212164D01*
X384793Y-211497D01*
X385493Y-211364D01*
X386193Y-211631D01*
X386693Y-212297D01*
G01X390393Y-219364D02*
Y-211364D01*
X392993Y-218031D01*
X395593Y-211364D01*
Y-219364D01*
G01X400993Y-211364D02*
Y-219364D01*
G01X398693Y-211364D02*
X403293D01*
G01X406893Y-219364D02*
Y-211364D01*
G01X411093D02*
Y-219364D01*
G01Y-215364D02*
X406893D01*
G01X414793Y-217764D02*
X415393Y-218697D01*
X416193Y-219231D01*
X417093Y-219364D01*
X417893Y-219231D01*
X418693Y-218564D01*
X419193Y-217764D01*
X419293Y-216964D01*
X419093Y-216031D01*
X418393Y-215364D01*
X417693Y-215097D01*
X416793D01*
G01X417693D02*
X418293Y-214697D01*
X418793Y-214031D01*
X418993Y-213231D01*
X418793Y-212431D01*
X418293Y-211764D01*
X417393Y-211364D01*
X416493Y-211497D01*
X415593Y-212031D01*
G01X422493Y-219364D02*
X424993Y-211364D01*
X427493Y-219364D01*
G01X426593Y-216564D02*
X423393D01*
G01X430793Y-219364D02*
Y-211364D01*
X432793D01*
X433593Y-211764D01*
X434193Y-212297D01*
X434693Y-213097D01*
X435093Y-214031D01*
X435193Y-215364D01*
X435093Y-216697D01*
X434693Y-217631D01*
X434193Y-218431D01*
X433593Y-218964D01*
X432793Y-219364D01*
X430793D01*
G01X440993Y-211364D02*
X440193Y-211631D01*
X439593Y-212297D01*
X439193Y-213097D01*
X438893Y-214164D01*
X438793Y-215364D01*
X438893Y-216564D01*
X439193Y-217631D01*
X439593Y-218431D01*
X440193Y-219097D01*
X440993Y-219364D01*
X441793Y-219097D01*
X442393Y-218431D01*
X442793Y-217631D01*
X443093Y-216564D01*
X443193Y-215364D01*
X443093Y-214164D01*
X442793Y-213097D01*
X442393Y-212297D01*
X441793Y-211631D01*
X440993Y-211364D01*
G01X380993Y-186364D02*
Y-194364D01*
G01X378693Y-186364D02*
X383293D01*
G01X387093Y-191031D02*
X387793Y-190097D01*
X388393Y-189564D01*
X389193Y-189297D01*
X389893Y-189564D01*
X390393Y-190097D01*
X390793Y-190897D01*
X390893Y-191831D01*
X390793Y-192631D01*
X390393Y-193431D01*
X389793Y-194097D01*
X389093Y-194364D01*
X388293Y-194097D01*
X387593Y-193298D01*
X387193Y-192097D01*
X387093Y-190764D01*
X387293Y-189031D01*
X387593Y-188097D01*
X388093Y-187164D01*
X388793Y-186497D01*
X389493Y-186364D01*
X390193Y-186631D01*
X390693Y-187297D01*
G01X394393Y-194364D02*
Y-186364D01*
X396993Y-193031D01*
X399593Y-186364D01*
Y-194364D01*
G01X401993Y-197031D02*
X407993D01*
G01X415193Y-187031D02*
X414593Y-186631D01*
X413893Y-186364D01*
X413093D01*
X412193Y-186764D01*
X411493Y-187431D01*
X410993Y-188231D01*
X410593Y-189564D01*
X410493Y-190764D01*
X410693Y-191964D01*
X410993Y-192764D01*
X411593Y-193564D01*
X412293Y-194097D01*
X412993Y-194364D01*
X413693D01*
X414393Y-194097D01*
X414993Y-193697D01*
X415493Y-193164D01*
G01X418393Y-194364D02*
Y-186364D01*
X420993Y-193031D01*
X423593Y-186364D01*
Y-194364D01*
G01X425993Y-197031D02*
X431993D01*
G01X434793Y-194364D02*
Y-186364D01*
X436793D01*
X437593Y-186764D01*
X438193Y-187297D01*
X438693Y-188097D01*
X439093Y-189031D01*
X439193Y-190364D01*
X439093Y-191697D01*
X438693Y-192631D01*
X438193Y-193431D01*
X437593Y-193964D01*
X436793Y-194364D01*
X434793D01*
G01X473793Y-244364D02*
Y-236364D01*
X475793D01*
X476593Y-236764D01*
X477193Y-237297D01*
X477693Y-238097D01*
X478093Y-239031D01*
X478193Y-240364D01*
X478093Y-241697D01*
X477693Y-242631D01*
X477193Y-243431D01*
X476593Y-243964D01*
X475793Y-244364D01*
X473793D01*
G01X503493D02*
Y-236364D01*
X502293Y-237964D01*
G01Y-244364D02*
X504693D01*
G01X509593Y-241031D02*
X510293Y-240097D01*
X510893Y-239564D01*
X511693Y-239297D01*
X512393Y-239564D01*
X512893Y-240097D01*
X513293Y-240897D01*
X513393Y-241831D01*
X513293Y-242631D01*
X512893Y-243431D01*
X512293Y-244097D01*
X511593Y-244364D01*
X510793Y-244097D01*
X510093Y-243298D01*
X509693Y-242097D01*
X509593Y-240764D01*
X509793Y-239031D01*
X510093Y-238097D01*
X510593Y-237164D01*
X511293Y-236497D01*
X511993Y-236364D01*
X512693Y-236631D01*
X513193Y-237297D01*
M02*
